# Altium SchDoc records: FPGA.SchDoc
|HEADER=Protel for Windows - Schematic Capture Binary File Version 5.0|Weight=3256|MinorVersion=2
|RECORD=31|FontIdCount=5|Size1=10|FontName1=Times New Roman|Size2=12|FontName2=Arial|Size3=8|FontName3=Arial|Size4=10|FontName4=Arial|Size5=12|Underline5=T|FontName5=Arial|UseMBCS=T|IsBOC=T|HotSpotGridOn=T|HotSpotGridSize=2|SheetStyle=12|SystemFont=4|BorderOn=T|SheetNumberSpaceSize=12|AreaColor=16317695|SnapGridOn=T|SnapGridSize=5|VisibleGridOn=T|VisibleGridSize=10|CustomX=2338|CustomX_Frac=58268|CustomY=1653|CustomY_Frac=54331|CustomXZones=8|CustomYZones=6|CustomMarginWidth=19|CustomMarginWidth_Frac=80000|ShowTemplateGraphics=T|TemplateFileName=C:\Users\<user>\Documents\Altium\AD20\Templates\Timecard.SchDot|Display_Unit=0
|RECORD=39|IsNotAccesible=T|OwnerPartId=-1|FileName=C:\Users\<user>\Documents\Altium\AD20\Templates\Timecard.SchDot
|RECORD=4|OwnerIndex=1|OwnerPartId=-1|Location.X=1594|Location.Y=39|Color=8388608|FontID=5|Text=timingcard.com|URL=http://timingcard.com
|RECORD=6|OwnerIndex=1|IndexInSheet=1|OwnerPartId=-1|LocationCount=2|X1=1680|Y1=35|X2=1576|Y2=35
|RECORD=4|OwnerIndex=1|IndexInSheet=2|OwnerPartId=-1|Location.X=1614|Location.X_Frac=42446|Location.Y=19|Location.Y_Frac=96838|FontID=2|Text==SheetNumber
|RECORD=4|OwnerIndex=1|IndexInSheet=3|OwnerPartId=-1|Location.X=1581|Location.X_Frac=42446|Location.Y=29|Location.Y_Frac=96838|Justification=3|FontID=3|Text=SHEET
|RECORD=4|OwnerIndex=1|IndexInSheet=4|OwnerPartId=-1|Location.X=1639|Location.X_Frac=42446|Location.Y=29|Location.Y_Frac=96838|Justification=3|FontID=3|Text=OF
|RECORD=6|OwnerIndex=1|IndexInSheet=5|OwnerPartId=-1|LineWidth=1|LocationCount=2|X1=1679|X1_Frac=42446|Y1=105|Y1_Frac=96838|X2=1576|Y2=106
|RECORD=4|OwnerIndex=1|IndexInSheet=6|OwnerPartId=-1|Location.X=1658|Location.Y=20|FontID=2|Text==SheetTotal
|RECORD=30|OwnerIndex=1|IndexInSheet=7|OwnerPartId=-1|Location.X=1578|Location.Y=53|Corner.X=1673|Corner.X_Frac=88801|Corner.Y=103|KeepAspect=T|FileName=C:\Users\<user>\Desktop\Timecard Logo\TIMECARD.jpg
|RECORD=6|OwnerIndex=1|IndexInSheet=8|OwnerPartId=-1|LineWidth=1|LocationCount=2|X1=1576|X1_Frac=3162|Y1=105|Y1_Frac=42446|X2=1576|Y2=20
|RECORD=6|OwnerIndex=1|IndexInSheet=9|OwnerPartId=-1|LocationCount=2|X1=1680|Y1=51|X2=1576|Y2=51
|RECORD=41|IndexInSheet=1|OwnerPartId=-1|Color=8388608|FontID=1|IsHidden=T|Text=*|Name=CurrentTime|ReadOnlyState=1
|RECORD=41|IndexInSheet=2|OwnerPartId=-1|Color=8388608|FontID=1|IsHidden=T|Text=*|Name=CurrentDate|ReadOnlyState=1
|RECORD=41|IndexInSheet=3|OwnerPartId=-1|Color=8388608|FontID=1|IsHidden=T|Text=*|Name=Time|ReadOnlyState=1
|RECORD=41|IndexInSheet=4|OwnerPartId=-1|Color=8388608|FontID=1|IsHidden=T|Text=*|Name=Date|ReadOnlyState=1
|RECORD=41|IndexInSheet=5|OwnerPartId=-1|Color=8388608|FontID=1|IsHidden=T|Text=*|Name=DocumentFullPathAndName|ReadOnlyState=1
|RECORD=41|IndexInSheet=6|OwnerPartId=-1|Color=8388608|FontID=1|IsHidden=T|Text=*|Name=DocumentName|ReadOnlyState=1
|RECORD=41|IndexInSheet=7|OwnerPartId=-1|Color=8388608|FontID=1|IsHidden=T|Text=*|Name=ModifiedDate|ReadOnlyState=1
|RECORD=41|IndexInSheet=8|OwnerPartId=-1|Color=8388608|FontID=1|IsHidden=T|Text=*|Name=ApprovedBy|ReadOnlyState=1
|RECORD=41|IndexInSheet=9|OwnerPartId=-1|Color=8388608|FontID=1|IsHidden=T|Text=*|Name=CheckedBy|ReadOnlyState=1
|RECORD=41|IndexInSheet=10|OwnerPartId=-1|Color=8388608|FontID=1|IsHidden=T|Text=<name>|Name=Author|ReadOnlyState=1
|RECORD=41|IndexInSheet=11|OwnerPartId=-1|Color=8388608|FontID=1|IsHidden=T|Text=*|Name=CompanyName|ReadOnlyState=1
|RECORD=41|IndexInSheet=12|OwnerPartId=-1|Color=8388608|FontID=1|IsHidden=T|Text=*|Name=DrawnBy|ReadOnlyState=1
|RECORD=41|IndexInSheet=13|OwnerPartId=-1|Color=8388608|FontID=1|IsHidden=T|Text=*|Name=Engineer|ReadOnlyState=1
|RECORD=41|IndexInSheet=14|OwnerPartId=-1|Color=8388608|FontID=1|IsHidden=T|Text=*|Name=Organization|ReadOnlyState=1
|RECORD=41|IndexInSheet=15|OwnerPartId=-1|Color=8388608|FontID=1|IsHidden=T|Text=*|Name=Address1|ReadOnlyState=1
|RECORD=41|IndexInSheet=16|OwnerPartId=-1|Color=8388608|FontID=1|IsHidden=T|Text=*|Name=Address2|ReadOnlyState=1
|RECORD=41|IndexInSheet=17|OwnerPartId=-1|Color=8388608|FontID=1|IsHidden=T|Text=*|Name=Address3|ReadOnlyState=1
|RECORD=41|IndexInSheet=18|OwnerPartId=-1|Color=8388608|FontID=1|IsHidden=T|Text=*|Name=Address4|ReadOnlyState=1
|RECORD=41|IndexInSheet=19|OwnerPartId=-1|Color=8388608|FontID=1|IsHidden=T|Text=Grandmaster FPGA Connectors|Name=Title|ReadOnlyState=1
|RECORD=41|IndexInSheet=20|OwnerPartId=-1|Color=8388608|FontID=1|IsHidden=T|Text=*|Name=DocumentNumber|ReadOnlyState=1
|RECORD=41|IndexInSheet=21|OwnerPartId=-1|Color=8388608|FontID=1|IsHidden=T|Text=A|Name=Revision|ReadOnlyState=1
|RECORD=41|IndexInSheet=22|OwnerPartId=-1|Color=8388608|FontID=1|IsHidden=T|Text=7|Name=SheetNumber|ReadOnlyState=1
|RECORD=41|IndexInSheet=23|OwnerPartId=-1|Color=8388608|FontID=1|IsHidden=T|Text=7|Name=SheetTotal|ReadOnlyState=1
|RECORD=41|IndexInSheet=24|OwnerPartId=-1|Color=8388608|FontID=1|IsHidden=T|Text=*|Name=Rule|ReadOnlyState=1
|RECORD=41|IndexInSheet=25|OwnerPartId=-1|Color=8388608|FontID=1|IsHidden=T|Text=*|Name=ImagePath|ReadOnlyState=1
|RECORD=41|IndexInSheet=26|OwnerPartId=-1|Color=8388608|FontID=1|IsHidden=T|Text=*|Name=ProjectName|ReadOnlyState=1
|RECORD=41|IndexInSheet=27|OwnerPartId=-1|Color=8388608|FontID=1|IsHidden=T|Text=*|Name=Application_BuildNumber|ReadOnlyState=1
|RECORD=41|IndexInSheet=28|OwnerPartId=-1|Location.X=21474|Location.X_Frac=83647|Location.Y=21464|Location.Y_Frac=83647|Color=8388608|FontID=1|IsHidden=T|Text=01910|Name=Customer
|RECORD=41|IndexInSheet=29|OwnerPartId=-1|Location.X=1000|Location.Y=10|Color=8388608|FontID=1|IsHidden=T|Text=*|Name=DocStatus
|RECORD=17|IndexInSheet=30|OwnerPartId=-1|ShowNetName=T|Location.X=410|Location.Y=1008|Orientation=1|Color=128|FontID=1|Text=+5.0V
|RECORD=22|IndexInSheet=31|OwnerPartId=-1|Location.X=460|Location.Y=938|Color=255|Orientation=1|Symbol=Thin Cross|IsActive=T|SuppressAll=T
|RECORD=22|IndexInSheet=32|OwnerPartId=-1|Location.X=460|Location.Y=928|Color=255|Orientation=1|Symbol=Thin Cross|IsActive=T|SuppressAll=T
|RECORD=22|IndexInSheet=33|OwnerPartId=-1|Location.X=460|Location.Y=918|Color=255|Orientation=1|Symbol=Thin Cross|IsActive=T|SuppressAll=T
|RECORD=22|IndexInSheet=34|OwnerPartId=-1|Location.X=460|Location.Y=908|Color=255|Orientation=1|Symbol=Thin Cross|IsActive=T|SuppressAll=T
|RECORD=22|IndexInSheet=35|OwnerPartId=-1|Location.X=460|Location.Y=718|Color=255|Orientation=1|Symbol=Thin Cross|IsActive=T|SuppressAll=T
|RECORD=22|IndexInSheet=36|OwnerPartId=-1|Location.X=460|Location.Y=708|Color=255|Orientation=1|Symbol=Thin Cross|IsActive=T|SuppressAll=T
|RECORD=22|IndexInSheet=37|OwnerPartId=-1|Location.X=460|Location.Y=598|Color=255|Orientation=1|Symbol=Thin Cross|IsActive=T|SuppressAll=T
|RECORD=17|IndexInSheet=38|OwnerPartId=-1|Style=4|ShowNetName=T|Location.X=410|Location.Y=568|Orientation=3|Color=128|FontID=1|Text=GND
|RECORD=17|IndexInSheet=39|OwnerPartId=-1|ShowNetName=T|Location.X=330|Location.Y=658|Orientation=2|Color=255|FontID=1|Text=KEY2|IsCrossSheetConnector=T
|RECORD=17|IndexInSheet=40|OwnerPartId=-1|ShowNetName=T|Location.X=330|Location.Y=638|Orientation=2|Color=255|FontID=1|Text=LED4|IsCrossSheetConnector=T
|RECORD=17|IndexInSheet=41|OwnerPartId=-1|ShowNetName=T|Location.X=330|Location.Y=628|Orientation=2|Color=255|FontID=1|Text=LED3|IsCrossSheetConnector=T
|RECORD=17|IndexInSheet=42|OwnerPartId=-1|ShowNetName=T|Location.X=330|Location.Y=618|Orientation=2|Color=255|FontID=1|Text=LED2|IsCrossSheetConnector=T
|RECORD=17|IndexInSheet=43|OwnerPartId=-1|ShowNetName=T|Location.X=330|Location.Y=608|Orientation=2|Color=255|FontID=1|Text=LED1|IsCrossSheetConnector=T
|RECORD=17|IndexInSheet=44|OwnerPartId=-1|ShowNetName=T|Location.X=600|Location.Y=1008|Orientation=1|Color=128|FontID=1|Text=+5.0V
|RECORD=22|IndexInSheet=45|OwnerPartId=-1|Location.X=580|Location.Y=938|Color=255|Orientation=1|Symbol=Thin Cross|IsActive=T|SuppressAll=T
|RECORD=22|IndexInSheet=46|OwnerPartId=-1|Location.X=580|Location.Y=928|Color=255|Orientation=1|Symbol=Thin Cross|IsActive=T|SuppressAll=T
|RECORD=22|IndexInSheet=47|OwnerPartId=-1|Location.X=580|Location.Y=738|Color=255|Orientation=1|Symbol=Thin Cross|IsActive=T|SuppressAll=T
|RECORD=22|IndexInSheet=48|OwnerPartId=-1|Location.X=580|Location.Y=668|Color=255|Orientation=1|Symbol=Thin Cross|IsActive=T|SuppressAll=T
|RECORD=22|IndexInSheet=49|OwnerPartId=-1|Location.X=580|Location.Y=658|Color=255|Orientation=1|Symbol=Thin Cross|IsActive=T|SuppressAll=T
|RECORD=22|IndexInSheet=50|OwnerPartId=-1|Location.X=580|Location.Y=638|Color=255|Orientation=1|Symbol=Thin Cross|IsActive=T|SuppressAll=T
|RECORD=22|IndexInSheet=51|OwnerPartId=-1|Location.X=580|Location.Y=628|Color=255|Orientation=1|Symbol=Thin Cross|IsActive=T|SuppressAll=T
|RECORD=22|IndexInSheet=52|OwnerPartId=-1|Location.X=580|Location.Y=618|Color=255|Orientation=1|Symbol=Thin Cross|IsActive=T|SuppressAll=T
|RECORD=22|IndexInSheet=53|OwnerPartId=-1|Location.X=580|Location.Y=608|Color=255|Orientation=1|Symbol=Thin Cross|IsActive=T|SuppressAll=T
|RECORD=22|IndexInSheet=54|OwnerPartId=-1|Location.X=580|Location.Y=598|Color=255|Orientation=1|Symbol=Thin Cross|IsActive=T|SuppressAll=T
|RECORD=17|IndexInSheet=55|OwnerPartId=-1|Style=4|ShowNetName=T|Location.X=600|Location.Y=568|Orientation=3|Color=128|FontID=1|Text=GND
|RECORD=17|IndexInSheet=56|OwnerPartId=-1|ShowNetName=T|Location.X=640|Location.Y=888|Color=255|FontID=1|Text=GPS1_RST|IsCrossSheetConnector=T
|RECORD=17|IndexInSheet=57|OwnerPartId=-1|ShowNetName=T|Location.X=640|Location.Y=838|Color=255|FontID=1|Text=GPS1_TP1|IsCrossSheetConnector=T
|RECORD=17|IndexInSheet=58|OwnerPartId=-1|ShowNetName=T|Location.X=640|Location.Y=828|Color=255|FontID=1|Text=GPS1_TP2|IsCrossSheetConnector=T
|RECORD=17|IndexInSheet=59|OwnerPartId=-1|Style=4|ShowNetName=T|Location.X=1130|Location.Y=568|Orientation=3|Color=128|FontID=1|Text=GND
|RECORD=17|IndexInSheet=60|OwnerPartId=-1|ShowNetName=T|Location.X=1060|Location.Y=598|Orientation=2|Color=255|FontID=1|Text=GPS1_RX|IsCrossSheetConnector=T
|RECORD=17|IndexInSheet=61|OwnerPartId=-1|ShowNetName=T|Location.X=1060|Location.Y=818|Orientation=2|Color=255|FontID=1|Text=MAC_ALARM|IsCrossSheetConnector=T
|RECORD=17|IndexInSheet=62|OwnerPartId=-1|ShowNetName=T|Location.X=1060|Location.Y=808|Orientation=2|Color=255|FontID=1|Text=MAC_BITE|IsCrossSheetConnector=T
|RECORD=17|IndexInSheet=63|OwnerPartId=-1|ShowNetName=T|Location.X=1060|Location.Y=828|Orientation=2|Color=255|FontID=1|Text=MAC_FREQ_CTRL|IsCrossSheetConnector=T
|RECORD=17|IndexInSheet=64|OwnerPartId=-1|ShowNetName=T|Location.X=1060|Location.Y=758|Orientation=2|Color=255|FontID=1|Text=FPGA_MAC_PPS_IN0-|IsCrossSheetConnector=T
|RECORD=17|IndexInSheet=65|OwnerPartId=-1|ShowNetName=T|Location.X=1060|Location.Y=728|Orientation=2|Color=255|FontID=1|Text=FPGA_MAC_PPS_IN1-|IsCrossSheetConnector=T
|RECORD=17|IndexInSheet=66|OwnerPartId=-1|ShowNetName=T|Location.X=1060|Location.Y=778|Orientation=2|Color=255|FontID=1|Text=FPGA_MAC_PPS_OUT-|IsCrossSheetConnector=T
|RECORD=17|IndexInSheet=67|OwnerPartId=-1|ShowNetName=T|Location.X=1060|Location.Y=938|Orientation=2|Color=255|FontID=1|Text=MAC_RF_OUT|IsCrossSheetConnector=T
|RECORD=17|IndexInSheet=68|OwnerPartId=-1|ShowNetName=T|Location.X=1060|Location.Y=888|Orientation=2|Color=255|FontID=1|Text=ANT1|IsCrossSheetConnector=T
|RECORD=17|IndexInSheet=69|OwnerPartId=-1|ShowNetName=T|Location.X=1060|Location.Y=878|Orientation=2|Color=255|FontID=1|Text=ANT2|IsCrossSheetConnector=T
|RECORD=17|IndexInSheet=70|OwnerPartId=-1|ShowNetName=T|Location.X=1060|Location.Y=868|Orientation=2|Color=255|FontID=1|Text=ANT3|IsCrossSheetConnector=T
|RECORD=17|IndexInSheet=71|OwnerPartId=-1|ShowNetName=T|Location.X=1060|Location.Y=858|Orientation=2|Color=255|FontID=1|Text=ANT4|IsCrossSheetConnector=T
|RECORD=17|IndexInSheet=72|OwnerPartId=-1|ShowNetName=T|Location.X=1060|Location.Y=688|Orientation=2|Color=255|FontID=1|Text=SDA|IsCrossSheetConnector=T
|RECORD=17|IndexInSheet=73|OwnerPartId=-1|ShowNetName=T|Location.X=1060|Location.Y=658|Orientation=2|Color=255|FontID=1|Text=SCL|IsCrossSheetConnector=T
|RECORD=17|IndexInSheet=74|OwnerPartId=-1|Style=4|ShowNetName=T|Location.X=1320|Location.Y=568|Orientation=3|Color=128|FontID=1|Text=GND
|RECORD=17|IndexInSheet=75|OwnerPartId=-1|ShowNetName=T|Location.X=1350|Location.Y=598|Color=255|FontID=1|Text=GPS1_TX|IsCrossSheetConnector=T
|RECORD=17|IndexInSheet=76|OwnerPartId=-1|ShowNetName=T|Location.X=1350|Location.Y=858|Color=255|FontID=1|Text=MAC_RX|IsCrossSheetConnector=T
|RECORD=17|IndexInSheet=77|OwnerPartId=-1|ShowNetName=T|Location.X=1350|Location.Y=868|Color=255|FontID=1|Text=MAC_TX|IsCrossSheetConnector=T
|RECORD=17|IndexInSheet=78|OwnerPartId=-1|ShowNetName=T|Location.X=1350|Location.Y=638|Color=255|FontID=1|Text=MAC_USB+|IsCrossSheetConnector=T
|RECORD=17|IndexInSheet=79|OwnerPartId=-1|ShowNetName=T|Location.X=1350|Location.Y=628|Color=255|FontID=1|Text=MAC_USB-|IsCrossSheetConnector=T
|RECORD=17|IndexInSheet=80|OwnerPartId=-1|ShowNetName=T|Location.X=1350|Location.Y=958|Color=255|FontID=1|Text=MAC_USB_PWR|IsCrossSheetConnector=T
|RECORD=17|IndexInSheet=81|OwnerPartId=-1|Style=4|ShowNetName=T|Location.X=400|Location.Y=68|Orientation=3|Color=128|FontID=1|Text=GND
|RECORD=22|IndexInSheet=82|OwnerPartId=-1|Location.X=460|Location.Y=128|Color=255|Orientation=1|Symbol=Thin Cross|IsActive=T|SuppressAll=T
|RECORD=17|IndexInSheet=83|OwnerPartId=-1|ShowNetName=T|Location.X=320|Location.Y=398|Orientation=2|Color=255|FontID=1|Text=PCIE_PERST|IsCrossSheetConnector=T
|RECORD=17|IndexInSheet=84|OwnerPartId=-1|ShowNetName=T|Location.X=320|Location.Y=388|Orientation=2|Color=255|FontID=1|Text=KEY1|IsCrossSheetConnector=T
|RECORD=17|IndexInSheet=85|OwnerPartId=-1|ShowNetName=T|Location.X=320|Location.Y=118|Orientation=2|Color=255|FontID=1|Text=FPGA_TCK|IsCrossSheetConnector=T
|RECORD=17|IndexInSheet=86|OwnerPartId=-1|ShowNetName=T|Location.X=320|Location.Y=108|Orientation=2|Color=255|FontID=1|Text=FPGA_TDO|IsCrossSheetConnector=T
|RECORD=17|IndexInSheet=87|OwnerPartId=-1|Style=4|ShowNetName=T|Location.X=620|Location.Y=68|Orientation=3|Color=128|FontID=1|Text=GND
|RECORD=22|IndexInSheet=88|OwnerPartId=-1|Location.X=580|Location.Y=128|Color=255|Orientation=1|Symbol=Thin Cross|IsActive=T|SuppressAll=T
|RECORD=17|IndexInSheet=89|OwnerPartId=-1|ShowNetName=T|Location.X=690|Location.Y=118|Color=255|FontID=1|Text=FPGA_TDI|IsCrossSheetConnector=T
|RECORD=17|IndexInSheet=90|OwnerPartId=-1|ShowNetName=T|Location.X=690|Location.Y=108|Color=255|FontID=1|Text=FPGA_TMS|IsCrossSheetConnector=T
|RECORD=22|IndexInSheet=91|OwnerPartId=-1|Location.X=1160|Location.Y=498|Color=255|Orientation=1|Symbol=Thin Cross|IsActive=T|SuppressAll=T
|RECORD=22|IndexInSheet=92|OwnerPartId=-1|Location.X=1160|Location.Y=488|Color=255|Orientation=1|Symbol=Thin Cross|IsActive=T|SuppressAll=T
|RECORD=22|IndexInSheet=93|OwnerPartId=-1|Location.X=1160|Location.Y=478|Color=255|Orientation=1|Symbol=Thin Cross|IsActive=T|SuppressAll=T
|RECORD=22|IndexInSheet=94|OwnerPartId=-1|Location.X=1160|Location.Y=468|Color=255|Orientation=1|Symbol=Thin Cross|IsActive=T|SuppressAll=T
|RECORD=22|IndexInSheet=95|OwnerPartId=-1|Location.X=1160|Location.Y=448|Color=255|Orientation=1|Symbol=Thin Cross|IsActive=T|SuppressAll=T
|RECORD=22|IndexInSheet=96|OwnerPartId=-1|Location.X=1160|Location.Y=438|Color=255|Orientation=1|Symbol=Thin Cross|IsActive=T|SuppressAll=T
|RECORD=22|IndexInSheet=97|OwnerPartId=-1|Location.X=1160|Location.Y=108|Color=255|Orientation=1|Symbol=Thin Cross|IsActive=T|SuppressAll=T
|RECORD=17|IndexInSheet=98|OwnerPartId=-1|Style=4|ShowNetName=T|Location.X=1110|Location.Y=78|Orientation=3|Color=128|FontID=1|Text=GND
|RECORD=17|IndexInSheet=99|OwnerPartId=-1|ShowNetName=T|Location.X=1060|Location.Y=418|Orientation=2|Color=255|FontID=1|Text=PCIE_TX3_P|IsCrossSheetConnector=T
|RECORD=17|IndexInSheet=100|OwnerPartId=-1|ShowNetName=T|Location.X=1060|Location.Y=408|Orientation=2|Color=255|FontID=1|Text=PCIE_TX3_N|IsCrossSheetConnector=T
|RECORD=17|IndexInSheet=101|OwnerPartId=-1|ShowNetName=T|Location.X=1060|Location.Y=388|Orientation=2|Color=255|FontID=1|Text=PCIE_RX3_P|IsCrossSheetConnector=T
|RECORD=17|IndexInSheet=102|OwnerPartId=-1|ShowNetName=T|Location.X=1060|Location.Y=378|Orientation=2|Color=255|FontID=1|Text=PCIE_RX3_N|IsCrossSheetConnector=T
|RECORD=17|IndexInSheet=103|OwnerPartId=-1|ShowNetName=T|Location.X=1060|Location.Y=358|Orientation=2|Color=255|FontID=1|Text=PCIE_TX0_P|IsCrossSheetConnector=T
|RECORD=17|IndexInSheet=104|OwnerPartId=-1|ShowNetName=T|Location.X=1060|Location.Y=348|Orientation=2|Color=255|FontID=1|Text=PCIE_TX0_N|IsCrossSheetConnector=T
|RECORD=17|IndexInSheet=105|OwnerPartId=-1|ShowNetName=T|Location.X=1060|Location.Y=328|Orientation=2|Color=255|FontID=1|Text=PCIE_RX0_P|IsCrossSheetConnector=T
|RECORD=17|IndexInSheet=106|OwnerPartId=-1|ShowNetName=T|Location.X=1060|Location.Y=318|Orientation=2|Color=255|FontID=1|Text=PCIE_RX0_N|IsCrossSheetConnector=T
|RECORD=43|IndexInSheet=107|OwnerPartId=-1|Location.X=1070|Location.Y=418|Color=255|Name=DIFFPAIR
|RECORD=41|OwnerIndex=118|OwnerPartId=-1|Location.X=1070|Location.Y=418|Color=8388608|FontID=1|IsHidden=T|Text=True|Name=DifferentialPair
|RECORD=43|IndexInSheet=108|OwnerPartId=-1|Location.X=1070|Location.Y=408|Color=255|Name=DIFFPAIR
|RECORD=41|OwnerIndex=120|OwnerPartId=-1|Location.X=1070|Location.Y=408|Color=8388608|FontID=1|IsHidden=T|Text=True|Name=DifferentialPair
|RECORD=43|IndexInSheet=109|OwnerPartId=-1|Location.X=1070|Location.Y=388|Color=255|Name=DIFFPAIR
|RECORD=41|OwnerIndex=122|OwnerPartId=-1|Location.X=1070|Location.Y=388|Color=8388608|FontID=1|IsHidden=T|Text=True|Name=DifferentialPair
|RECORD=43|IndexInSheet=110|OwnerPartId=-1|Location.X=1070|Location.Y=378|Color=255|Name=DIFFPAIR
|RECORD=41|OwnerIndex=124|OwnerPartId=-1|Location.X=1070|Location.Y=378|Color=8388608|FontID=1|IsHidden=T|Text=True|Name=DifferentialPair
|RECORD=43|IndexInSheet=111|OwnerPartId=-1|Location.X=1070|Location.Y=358|Color=255|Name=DIFFPAIR
|RECORD=41|OwnerIndex=126|OwnerPartId=-1|Location.X=1070|Location.Y=358|Color=8388608|FontID=1|IsHidden=T|Text=True|Name=DifferentialPair
|RECORD=43|IndexInSheet=112|OwnerPartId=-1|Location.X=1070|Location.Y=348|Color=255|Name=DIFFPAIR
|RECORD=41|OwnerIndex=128|OwnerPartId=-1|Location.X=1070|Location.Y=348|Color=8388608|FontID=1|IsHidden=T|Text=True|Name=DifferentialPair
|RECORD=43|IndexInSheet=113|OwnerPartId=-1|Location.X=1070|Location.Y=328|Color=255|Name=DIFFPAIR
|RECORD=41|OwnerIndex=130|OwnerPartId=-1|Location.X=1070|Location.Y=328|Color=8388608|FontID=1|IsHidden=T|Text=True|Name=DifferentialPair
|RECORD=43|IndexInSheet=114|OwnerPartId=-1|Location.X=1070|Location.Y=318|Color=255|Name=DIFFPAIR
|RECORD=41|OwnerIndex=132|OwnerPartId=-1|Location.X=1070|Location.Y=318|Color=8388608|FontID=1|IsHidden=T|Text=True|Name=DifferentialPair
|RECORD=22|IndexInSheet=115|OwnerPartId=-1|Location.X=1280|Location.Y=498|Color=255|Orientation=1|Symbol=Thin Cross|IsActive=T|SuppressAll=T
|RECORD=22|IndexInSheet=116|OwnerPartId=-1|Location.X=1280|Location.Y=488|Color=255|Orientation=1|Symbol=Thin Cross|IsActive=T|SuppressAll=T
|RECORD=22|IndexInSheet=117|OwnerPartId=-1|Location.X=1280|Location.Y=478|Color=255|Orientation=1|Symbol=Thin Cross|IsActive=T|SuppressAll=T
|RECORD=22|IndexInSheet=118|OwnerPartId=-1|Location.X=1280|Location.Y=468|Color=255|Orientation=1|Symbol=Thin Cross|IsActive=T|SuppressAll=T
|RECORD=22|IndexInSheet=119|OwnerPartId=-1|Location.X=1280|Location.Y=108|Color=255|Orientation=1|Symbol=Thin Cross|IsActive=T|SuppressAll=T
|RECORD=17|IndexInSheet=120|OwnerPartId=-1|Style=4|ShowNetName=T|Location.X=1310|Location.Y=78|Orientation=3|Color=128|FontID=1|Text=GND
|RECORD=17|IndexInSheet=121|OwnerPartId=-1|ShowNetName=T|Location.X=1360|Location.Y=448|Color=255|FontID=1|Text=PCIE_TX2_P|IsCrossSheetConnector=T
|RECORD=17|IndexInSheet=122|OwnerPartId=-1|ShowNetName=T|Location.X=1360|Location.Y=438|Color=255|FontID=1|Text=PCIE_TX2_N|IsCrossSheetConnector=T
|RECORD=17|IndexInSheet=123|OwnerPartId=-1|ShowNetName=T|Location.X=1360|Location.Y=418|Color=255|FontID=1|Text=PCIE_RX2_P|IsCrossSheetConnector=T
|RECORD=17|IndexInSheet=124|OwnerPartId=-1|ShowNetName=T|Location.X=1360|Location.Y=408|Color=255|FontID=1|Text=PCIE_RX2_N|IsCrossSheetConnector=T
|RECORD=17|IndexInSheet=125|OwnerPartId=-1|ShowNetName=T|Location.X=1360|Location.Y=388|Color=255|FontID=1|Text=PCIE_TX1_P|IsCrossSheetConnector=T
|RECORD=17|IndexInSheet=126|OwnerPartId=-1|ShowNetName=T|Location.X=1360|Location.Y=378|Color=255|FontID=1|Text=PCIE_TX1_N|IsCrossSheetConnector=T
|RECORD=17|IndexInSheet=127|OwnerPartId=-1|ShowNetName=T|Location.X=1360|Location.Y=358|Color=255|FontID=1|Text=PCIE_RX1_P|IsCrossSheetConnector=T
|RECORD=17|IndexInSheet=128|OwnerPartId=-1|ShowNetName=T|Location.X=1360|Location.Y=348|Color=255|FontID=1|Text=PCIE_RX1_N|IsCrossSheetConnector=T
|RECORD=17|IndexInSheet=129|OwnerPartId=-1|ShowNetName=T|Location.X=1360|Location.Y=328|Color=255|FontID=1|Text=PCIE_CLK_P|IsCrossSheetConnector=T
|RECORD=17|IndexInSheet=130|OwnerPartId=-1|ShowNetName=T|Location.X=1360|Location.Y=318|Color=255|FontID=1|Text=PCIE_CLK_N|IsCrossSheetConnector=T
|RECORD=43|IndexInSheet=131|OwnerPartId=-1|Location.X=1330|Location.Y=448|Color=255|Name=DIFFPAIR
|RECORD=41|OwnerIndex=150|OwnerPartId=-1|Location.X=1330|Location.Y=448|Color=8388608|FontID=1|IsHidden=T|Text=True|Name=DifferentialPair
|RECORD=43|IndexInSheet=132|OwnerPartId=-1|Location.X=1330|Location.Y=438|Color=255|Name=DIFFPAIR
|RECORD=41|OwnerIndex=152|OwnerPartId=-1|Location.X=1330|Location.Y=438|Color=8388608|FontID=1|IsHidden=T|Text=True|Name=DifferentialPair
|RECORD=43|IndexInSheet=133|OwnerPartId=-1|Location.X=1330|Location.Y=418|Color=255|Name=DIFFPAIR
|RECORD=41|OwnerIndex=154|OwnerPartId=-1|Location.X=1330|Location.Y=418|Color=8388608|FontID=1|IsHidden=T|Text=True|Name=DifferentialPair
|RECORD=43|IndexInSheet=134|OwnerPartId=-1|Location.X=1330|Location.Y=408|Color=255|Name=DIFFPAIR
|RECORD=41|OwnerIndex=156|OwnerPartId=-1|Location.X=1330|Location.Y=408|Color=8388608|FontID=1|IsHidden=T|Text=True|Name=DifferentialPair
|RECORD=43|IndexInSheet=135|OwnerPartId=-1|Location.X=1330|Location.Y=388|Color=255|Name=DIFFPAIR
|RECORD=41|OwnerIndex=158|OwnerPartId=-1|Location.X=1330|Location.Y=388|Color=8388608|FontID=1|IsHidden=T|Text=True|Name=DifferentialPair
|RECORD=43|IndexInSheet=136|OwnerPartId=-1|Location.X=1330|Location.Y=378|Color=255|Name=DIFFPAIR
|RECORD=41|OwnerIndex=160|OwnerPartId=-1|Location.X=1330|Location.Y=378|Color=8388608|FontID=1|IsHidden=T|Text=True|Name=DifferentialPair
|RECORD=43|IndexInSheet=137|OwnerPartId=-1|Location.X=1330|Location.Y=358|Color=255|Name=DIFFPAIR
|RECORD=41|OwnerIndex=162|OwnerPartId=-1|Location.X=1330|Location.Y=358|Color=8388608|FontID=1|IsHidden=T|Text=True|Name=DifferentialPair
|RECORD=43|IndexInSheet=138|OwnerPartId=-1|Location.X=1330|Location.Y=348|Color=255|Name=DIFFPAIR
|RECORD=41|OwnerIndex=164|OwnerPartId=-1|Location.X=1330|Location.Y=348|Color=8388608|FontID=1|IsHidden=T|Text=True|Name=DifferentialPair
|RECORD=43|IndexInSheet=139|OwnerPartId=-1|Location.X=1330|Location.Y=328|Color=255|Name=DIFFPAIR
|RECORD=41|OwnerIndex=166|OwnerPartId=-1|Location.X=1330|Location.Y=328|Color=8388608|FontID=1|IsHidden=T|Text=True|Name=DifferentialPair
|RECORD=43|IndexInSheet=140|OwnerPartId=-1|Location.X=1330|Location.Y=318|Color=255|Name=DIFFPAIR
|RECORD=41|OwnerIndex=168|OwnerPartId=-1|Location.X=1330|Location.Y=318|Color=8388608|FontID=1|IsHidden=T|Text=True|Name=DifferentialPair
|RECORD=22|IndexInSheet=141|OwnerPartId=-1|Location.X=460|Location.Y=838|Color=255|Orientation=1|Symbol=Thin Cross|IsActive=T|SuppressAll=T
|RECORD=22|IndexInSheet=142|OwnerPartId=-1|Location.X=460|Location.Y=828|Color=255|Orientation=1|Symbol=Thin Cross|IsActive=T|SuppressAll=T
|RECORD=22|IndexInSheet=143|OwnerPartId=-1|Location.X=460|Location.Y=808|Color=255|Orientation=1|Symbol=Thin Cross|IsActive=T|SuppressAll=T
|RECORD=22|IndexInSheet=144|OwnerPartId=-1|Location.X=460|Location.Y=788|Color=255|Orientation=1|Symbol=Thin Cross|IsActive=T|SuppressAll=T
|RECORD=22|IndexInSheet=145|OwnerPartId=-1|Location.X=460|Location.Y=758|Color=255|Orientation=1|Symbol=Thin Cross|IsActive=T|SuppressAll=T
|RECORD=22|IndexInSheet=146|OwnerPartId=-1|Location.X=460|Location.Y=738|Color=255|Orientation=1|Symbol=Thin Cross|IsActive=T|SuppressAll=T
|RECORD=22|IndexInSheet=147|OwnerPartId=-1|Location.X=460|Location.Y=728|Color=255|Orientation=1|Symbol=Thin Cross|IsActive=T|SuppressAll=T
|RECORD=22|IndexInSheet=148|OwnerPartId=-1|Location.X=460|Location.Y=688|Color=255|Orientation=1|Symbol=Thin Cross|IsActive=T|SuppressAll=T
|RECORD=22|IndexInSheet=149|OwnerPartId=-1|Location.X=460|Location.Y=678|Color=255|Orientation=1|Symbol=Thin Cross|IsActive=T|SuppressAll=T
|RECORD=22|IndexInSheet=150|OwnerPartId=-1|Location.X=460|Location.Y=668|Color=255|Orientation=1|Symbol=Thin Cross|IsActive=T|SuppressAll=T
|RECORD=22|IndexInSheet=151|OwnerPartId=-1|Location.X=460|Location.Y=588|Color=255|Orientation=1|Symbol=Thin Cross|IsActive=T|SuppressAll=T
|RECORD=22|IndexInSheet=152|OwnerPartId=-1|Location.X=460|Location.Y=578|Color=255|Orientation=1|Symbol=Thin Cross|IsActive=T|SuppressAll=T
|RECORD=22|IndexInSheet=153|OwnerPartId=-1|Location.X=580|Location.Y=588|Color=255|Orientation=1|Symbol=Thin Cross|IsActive=T|SuppressAll=T
|RECORD=22|IndexInSheet=154|OwnerPartId=-1|Location.X=580|Location.Y=578|Color=255|Orientation=1|Symbol=Thin Cross|IsActive=T|SuppressAll=T
|RECORD=22|IndexInSheet=155|OwnerPartId=-1|Location.X=580|Location.Y=708|Color=255|Orientation=1|Symbol=Thin Cross|IsActive=T|SuppressAll=T
|RECORD=22|IndexInSheet=156|OwnerPartId=-1|Location.X=580|Location.Y=788|Color=255|Orientation=1|Symbol=Thin Cross|IsActive=T|SuppressAll=T
|RECORD=22|IndexInSheet=157|OwnerPartId=-1|Location.X=580|Location.Y=808|Color=255|Orientation=1|Symbol=Thin Cross|IsActive=T|SuppressAll=T
|RECORD=22|IndexInSheet=158|OwnerPartId=-1|Location.X=580|Location.Y=818|Color=255|Orientation=1|Symbol=Thin Cross|IsActive=T|SuppressAll=T
|RECORD=22|IndexInSheet=159|OwnerPartId=-1|Location.X=580|Location.Y=858|Color=255|Orientation=1|Symbol=Thin Cross|IsActive=T|SuppressAll=T
|RECORD=22|IndexInSheet=160|OwnerPartId=-1|Location.X=580|Location.Y=868|Color=255|Orientation=1|Symbol=Thin Cross|IsActive=T|SuppressAll=T
|RECORD=22|IndexInSheet=161|OwnerPartId=-1|Location.X=580|Location.Y=878|Color=255|Orientation=1|Symbol=Thin Cross|IsActive=T|SuppressAll=T
|RECORD=22|IndexInSheet=162|OwnerPartId=-1|Location.X=580|Location.Y=908|Color=255|Orientation=1|Symbol=Thin Cross|IsActive=T|SuppressAll=T
|RECORD=22|IndexInSheet=163|OwnerPartId=-1|Location.X=580|Location.Y=918|Color=255|Orientation=1|Symbol=Thin Cross|IsActive=T|SuppressAll=T
|RECORD=22|IndexInSheet=164|OwnerPartId=-1|Location.X=1170|Location.Y=988|Color=255|Orientation=1|Symbol=Thin Cross|IsActive=T|SuppressAll=T
|RECORD=22|IndexInSheet=165|OwnerPartId=-1|Location.X=1170|Location.Y=968|Color=255|Orientation=1|Symbol=Thin Cross|IsActive=T|SuppressAll=T
|RECORD=22|IndexInSheet=166|OwnerPartId=-1|Location.X=1170|Location.Y=978|Color=255|Orientation=1|Symbol=Thin Cross|IsActive=T|SuppressAll=T
|RECORD=22|IndexInSheet=167|OwnerPartId=-1|Location.X=1170|Location.Y=958|Color=255|Orientation=1|Symbol=Thin Cross|IsActive=T|SuppressAll=T
|RECORD=22|IndexInSheet=168|OwnerPartId=-1|Location.X=1290|Location.Y=978|Color=255|Orientation=1|Symbol=Thin Cross|IsActive=T|SuppressAll=T
|RECORD=22|IndexInSheet=169|OwnerPartId=-1|Location.X=1290|Location.Y=988|Color=255|Orientation=1|Symbol=Thin Cross|IsActive=T|SuppressAll=T
|RECORD=22|IndexInSheet=170|OwnerPartId=-1|Location.X=1290|Location.Y=938|Color=255|Orientation=1|Symbol=Thin Cross|IsActive=T|SuppressAll=T
|RECORD=22|IndexInSheet=171|OwnerPartId=-1|Location.X=1290|Location.Y=928|Color=255|Orientation=1|Symbol=Thin Cross|IsActive=T|SuppressAll=T
|RECORD=22|IndexInSheet=172|OwnerPartId=-1|Location.X=1170|Location.Y=918|Color=255|Orientation=1|Symbol=Thin Cross|IsActive=T|SuppressAll=T
|RECORD=22|IndexInSheet=173|OwnerPartId=-1|Location.X=1170|Location.Y=908|Color=255|Orientation=1|Symbol=Thin Cross|IsActive=T|SuppressAll=T
|RECORD=22|IndexInSheet=174|OwnerPartId=-1|Location.X=1290|Location.Y=908|Color=255|Orientation=1|Symbol=Thin Cross|IsActive=T|SuppressAll=T
|RECORD=22|IndexInSheet=175|OwnerPartId=-1|Location.X=1290|Location.Y=888|Color=255|Orientation=1|Symbol=Thin Cross|IsActive=T|SuppressAll=T
|RECORD=22|IndexInSheet=176|OwnerPartId=-1|Location.X=1290|Location.Y=878|Color=255|Orientation=1|Symbol=Thin Cross|IsActive=T|SuppressAll=T
|RECORD=22|IndexInSheet=177|OwnerPartId=-1|Location.X=1170|Location.Y=838|Color=255|Orientation=1|Symbol=Thin Cross|IsActive=T|SuppressAll=T
|RECORD=22|IndexInSheet=178|OwnerPartId=-1|Location.X=1290|Location.Y=838|Color=255|Orientation=1|Symbol=Thin Cross|IsActive=T|SuppressAll=T
|RECORD=22|IndexInSheet=179|OwnerPartId=-1|Location.X=1290|Location.Y=818|Color=255|Orientation=1|Symbol=Thin Cross|IsActive=T|SuppressAll=T
|RECORD=22|IndexInSheet=180|OwnerPartId=-1|Location.X=1290|Location.Y=808|Color=255|Orientation=1|Symbol=Thin Cross|IsActive=T|SuppressAll=T
|RECORD=22|IndexInSheet=181|OwnerPartId=-1|Location.X=1290|Location.Y=788|Color=255|Orientation=1|Symbol=Thin Cross|IsActive=T|SuppressAll=T
|RECORD=22|IndexInSheet=182|OwnerPartId=-1|Location.X=1290|Location.Y=778|Color=255|Orientation=1|Symbol=Thin Cross|IsActive=T|SuppressAll=T
|RECORD=22|IndexInSheet=183|OwnerPartId=-1|Location.X=1290|Location.Y=778|Color=255|Orientation=1|Symbol=Thin Cross|IsActive=T|SuppressAll=T
|RECORD=22|IndexInSheet=184|OwnerPartId=-1|Location.X=1290|Location.Y=768|Color=255|Orientation=1|Symbol=Thin Cross|IsActive=T|SuppressAll=T
|RECORD=22|IndexInSheet=185|OwnerPartId=-1|Location.X=1290|Location.Y=758|Color=255|Orientation=1|Symbol=Thin Cross|IsActive=T|SuppressAll=T
|RECORD=22|IndexInSheet=186|OwnerPartId=-1|Location.X=1170|Location.Y=718|Color=255|Orientation=1|Symbol=Thin Cross|IsActive=T|SuppressAll=T
|RECORD=22|IndexInSheet=187|OwnerPartId=-1|Location.X=1170|Location.Y=708|Color=255|Orientation=1|Symbol=Thin Cross|IsActive=T|SuppressAll=T
|RECORD=22|IndexInSheet=188|OwnerPartId=-1|Location.X=1290|Location.Y=738|Color=255|Orientation=1|Symbol=Thin Cross|IsActive=T|SuppressAll=T
|RECORD=22|IndexInSheet=189|OwnerPartId=-1|Location.X=1290|Location.Y=728|Color=255|Orientation=1|Symbol=Thin Cross|IsActive=T|SuppressAll=T
|RECORD=22|IndexInSheet=190|OwnerPartId=-1|Location.X=1290|Location.Y=718|Color=255|Orientation=1|Symbol=Thin Cross|IsActive=T|SuppressAll=T
|RECORD=22|IndexInSheet=191|OwnerPartId=-1|Location.X=1290|Location.Y=708|Color=255|Orientation=1|Symbol=Thin Cross|IsActive=T|SuppressAll=T
|RECORD=22|IndexInSheet=192|OwnerPartId=-1|Location.X=1290|Location.Y=688|Color=255|Orientation=1|Symbol=Thin Cross|IsActive=T|SuppressAll=T
|RECORD=22|IndexInSheet=193|OwnerPartId=-1|Location.X=1290|Location.Y=668|Color=255|Orientation=1|Symbol=Thin Cross|IsActive=T|SuppressAll=T
|RECORD=22|IndexInSheet=194|OwnerPartId=-1|Location.X=1290|Location.Y=658|Color=255|Orientation=1|Symbol=Thin Cross|IsActive=T|SuppressAll=T
|RECORD=22|IndexInSheet=195|OwnerPartId=-1|Location.X=1170|Location.Y=678|Color=255|Orientation=1|Symbol=Thin Cross|IsActive=T|SuppressAll=T
|RECORD=22|IndexInSheet=196|OwnerPartId=-1|Location.X=1170|Location.Y=668|Color=255|Orientation=1|Symbol=Thin Cross|IsActive=T|SuppressAll=T
|RECORD=22|IndexInSheet=197|OwnerPartId=-1|Location.X=1170|Location.Y=628|Color=255|Orientation=1|Symbol=Thin Cross|IsActive=T|SuppressAll=T
|RECORD=22|IndexInSheet=198|OwnerPartId=-1|Location.X=1170|Location.Y=618|Color=255|Orientation=1|Symbol=Thin Cross|IsActive=T|SuppressAll=T
|RECORD=22|IndexInSheet=199|OwnerPartId=-1|Location.X=1290|Location.Y=618|Color=255|Orientation=1|Symbol=Thin Cross|IsActive=T|SuppressAll=T
|RECORD=22|IndexInSheet=200|OwnerPartId=-1|Location.X=1290|Location.Y=608|Color=255|Orientation=1|Symbol=Thin Cross|IsActive=T|SuppressAll=T
|RECORD=22|IndexInSheet=201|OwnerPartId=-1|Location.X=1290|Location.Y=588|Color=255|Orientation=1|Symbol=Thin Cross|IsActive=T|SuppressAll=T
|RECORD=22|IndexInSheet=202|OwnerPartId=-1|Location.X=1290|Location.Y=578|Color=255|Orientation=1|Symbol=Thin Cross|IsActive=T|SuppressAll=T
|RECORD=22|IndexInSheet=203|OwnerPartId=-1|Location.X=1170|Location.Y=588|Color=255|Orientation=1|Symbol=Thin Cross|IsActive=T|SuppressAll=T
|RECORD=22|IndexInSheet=204|OwnerPartId=-1|Location.X=1170|Location.Y=578|Color=255|Orientation=1|Symbol=Thin Cross|IsActive=T|SuppressAll=T
|RECORD=22|IndexInSheet=205|OwnerPartId=-1|Location.X=1280|Location.Y=428|Color=255|Orientation=1|Symbol=Thin Cross|IsActive=T|SuppressAll=T
|RECORD=22|IndexInSheet=206|OwnerPartId=-1|Location.X=1280|Location.Y=398|Color=255|Orientation=1|Symbol=Thin Cross|IsActive=T|SuppressAll=T
|RECORD=22|IndexInSheet=207|OwnerPartId=-1|Location.X=1280|Location.Y=368|Color=255|Orientation=1|Symbol=Thin Cross|IsActive=T|SuppressAll=T
|RECORD=22|IndexInSheet=208|OwnerPartId=-1|Location.X=1280|Location.Y=338|Color=255|Orientation=1|Symbol=Thin Cross|IsActive=T|SuppressAll=T
|RECORD=22|IndexInSheet=209|OwnerPartId=-1|Location.X=1280|Location.Y=298|Color=255|Orientation=1|Symbol=Thin Cross|IsActive=T|SuppressAll=T
|RECORD=22|IndexInSheet=210|OwnerPartId=-1|Location.X=1280|Location.Y=288|Color=255|Orientation=1|Symbol=Thin Cross|IsActive=T|SuppressAll=T
|RECORD=22|IndexInSheet=211|OwnerPartId=-1|Location.X=1280|Location.Y=278|Color=255|Orientation=1|Symbol=Thin Cross|IsActive=T|SuppressAll=T
|RECORD=22|IndexInSheet=212|OwnerPartId=-1|Location.X=1280|Location.Y=268|Color=255|Orientation=1|Symbol=Thin Cross|IsActive=T|SuppressAll=T
|RECORD=22|IndexInSheet=213|OwnerPartId=-1|Location.X=1160|Location.Y=298|Color=255|Orientation=1|Symbol=Thin Cross|IsActive=T|SuppressAll=T
|RECORD=22|IndexInSheet=214|OwnerPartId=-1|Location.X=1160|Location.Y=288|Color=255|Orientation=1|Symbol=Thin Cross|IsActive=T|SuppressAll=T
|RECORD=22|IndexInSheet=215|OwnerPartId=-1|Location.X=1160|Location.Y=278|Color=255|Orientation=1|Symbol=Thin Cross|IsActive=T|SuppressAll=T
|RECORD=22|IndexInSheet=216|OwnerPartId=-1|Location.X=1160|Location.Y=268|Color=255|Orientation=1|Symbol=Thin Cross|IsActive=T|SuppressAll=T
|RECORD=22|IndexInSheet=217|OwnerPartId=-1|Location.X=1160|Location.Y=248|Color=255|Orientation=1|Symbol=Thin Cross|IsActive=T|SuppressAll=T
|RECORD=22|IndexInSheet=218|OwnerPartId=-1|Location.X=1160|Location.Y=238|Color=255|Orientation=1|Symbol=Thin Cross|IsActive=T|SuppressAll=T
|RECORD=22|IndexInSheet=219|OwnerPartId=-1|Location.X=1160|Location.Y=228|Color=255|Orientation=1|Symbol=Thin Cross|IsActive=T|SuppressAll=T
|RECORD=22|IndexInSheet=220|OwnerPartId=-1|Location.X=1160|Location.Y=218|Color=255|Orientation=1|Symbol=Thin Cross|IsActive=T|SuppressAll=T
|RECORD=22|IndexInSheet=221|OwnerPartId=-1|Location.X=1280|Location.Y=218|Color=255|Orientation=1|Symbol=Thin Cross|IsActive=T|SuppressAll=T
|RECORD=22|IndexInSheet=222|OwnerPartId=-1|Location.X=1280|Location.Y=228|Color=255|Orientation=1|Symbol=Thin Cross|IsActive=T|SuppressAll=T
|RECORD=22|IndexInSheet=223|OwnerPartId=-1|Location.X=1280|Location.Y=238|Color=255|Orientation=1|Symbol=Thin Cross|IsActive=T|SuppressAll=T
|RECORD=22|IndexInSheet=224|OwnerPartId=-1|Location.X=1280|Location.Y=248|Color=255|Orientation=1|Symbol=Thin Cross|IsActive=T|SuppressAll=T
|RECORD=22|IndexInSheet=225|OwnerPartId=-1|Location.X=1280|Location.Y=198|Color=255|Orientation=1|Symbol=Thin Cross|IsActive=T|SuppressAll=T
|RECORD=22|IndexInSheet=226|OwnerPartId=-1|Location.X=1280|Location.Y=188|Color=255|Orientation=1|Symbol=Thin Cross|IsActive=T|SuppressAll=T
|RECORD=22|IndexInSheet=227|OwnerPartId=-1|Location.X=1280|Location.Y=178|Color=255|Orientation=1|Symbol=Thin Cross|IsActive=T|SuppressAll=T
|RECORD=22|IndexInSheet=228|OwnerPartId=-1|Location.X=1280|Location.Y=168|Color=255|Orientation=1|Symbol=Thin Cross|IsActive=T|SuppressAll=T
|RECORD=22|IndexInSheet=229|OwnerPartId=-1|Location.X=1160|Location.Y=198|Color=255|Orientation=1|Symbol=Thin Cross|IsActive=T|SuppressAll=T
|RECORD=22|IndexInSheet=230|OwnerPartId=-1|Location.X=1160|Location.Y=188|Color=255|Orientation=1|Symbol=Thin Cross|IsActive=T|SuppressAll=T
|RECORD=22|IndexInSheet=231|OwnerPartId=-1|Location.X=1160|Location.Y=178|Color=255|Orientation=1|Symbol=Thin Cross|IsActive=T|SuppressAll=T
|RECORD=22|IndexInSheet=232|OwnerPartId=-1|Location.X=1160|Location.Y=168|Color=255|Orientation=1|Symbol=Thin Cross|IsActive=T|SuppressAll=T
|RECORD=22|IndexInSheet=233|OwnerPartId=-1|Location.X=1160|Location.Y=148|Color=255|Orientation=1|Symbol=Thin Cross|IsActive=T|SuppressAll=T
|RECORD=22|IndexInSheet=234|OwnerPartId=-1|Location.X=1160|Location.Y=138|Color=255|Orientation=1|Symbol=Thin Cross|IsActive=T|SuppressAll=T
|RECORD=22|IndexInSheet=235|OwnerPartId=-1|Location.X=1160|Location.Y=118|Color=255|Orientation=1|Symbol=Thin Cross|IsActive=T|SuppressAll=T
|RECORD=22|IndexInSheet=236|OwnerPartId=-1|Location.X=1160|Location.Y=128|Color=255|Orientation=1|Symbol=Thin Cross|IsActive=T|SuppressAll=T
|RECORD=22|IndexInSheet=237|OwnerPartId=-1|Location.X=1160|Location.Y=98|Color=255|Orientation=1|Symbol=Thin Cross|IsActive=T|SuppressAll=T
|RECORD=22|IndexInSheet=238|OwnerPartId=-1|Location.X=1160|Location.Y=88|Color=255|Orientation=1|Symbol=Thin Cross|IsActive=T|SuppressAll=T
|RECORD=22|IndexInSheet=239|OwnerPartId=-1|Location.X=1280|Location.Y=88|Color=255|Orientation=1|Symbol=Thin Cross|IsActive=T|SuppressAll=T
|RECORD=22|IndexInSheet=240|OwnerPartId=-1|Location.X=1280|Location.Y=98|Color=255|Orientation=1|Symbol=Thin Cross|IsActive=T|SuppressAll=T
|RECORD=22|IndexInSheet=241|OwnerPartId=-1|Location.X=1280|Location.Y=118|Color=255|Orientation=1|Symbol=Thin Cross|IsActive=T|SuppressAll=T
|RECORD=22|IndexInSheet=242|OwnerPartId=-1|Location.X=1280|Location.Y=128|Color=255|Orientation=1|Symbol=Thin Cross|IsActive=T|SuppressAll=T
|RECORD=22|IndexInSheet=243|OwnerPartId=-1|Location.X=1280|Location.Y=138|Color=255|Orientation=1|Symbol=Thin Cross|IsActive=T|SuppressAll=T
|RECORD=22|IndexInSheet=244|OwnerPartId=-1|Location.X=1280|Location.Y=148|Color=255|Orientation=1|Symbol=Thin Cross|IsActive=T|SuppressAll=T
|RECORD=22|IndexInSheet=245|OwnerPartId=-1|Location.X=460|Location.Y=488|Color=255|Orientation=1|Symbol=Thin Cross|IsActive=T|SuppressAll=T
|RECORD=22|IndexInSheet=246|OwnerPartId=-1|Location.X=460|Location.Y=478|Color=255|Orientation=1|Symbol=Thin Cross|IsActive=T|SuppressAll=T
|RECORD=22|IndexInSheet=247|OwnerPartId=-1|Location.X=460|Location.Y=468|Color=255|Orientation=1|Symbol=Thin Cross|IsActive=T|SuppressAll=T
|RECORD=22|IndexInSheet=248|OwnerPartId=-1|Location.X=580|Location.Y=488|Color=255|Orientation=1|Symbol=Thin Cross|IsActive=T|SuppressAll=T
|RECORD=22|IndexInSheet=249|OwnerPartId=-1|Location.X=580|Location.Y=478|Color=255|Orientation=1|Symbol=Thin Cross|IsActive=T|SuppressAll=T
|RECORD=22|IndexInSheet=250|OwnerPartId=-1|Location.X=580|Location.Y=468|Color=255|Orientation=1|Symbol=Thin Cross|IsActive=T|SuppressAll=T
|RECORD=22|IndexInSheet=251|OwnerPartId=-1|Location.X=580|Location.Y=448|Color=255|Orientation=1|Symbol=Thin Cross|IsActive=T|SuppressAll=T
|RECORD=22|IndexInSheet=252|OwnerPartId=-1|Location.X=580|Location.Y=438|Color=255|Orientation=1|Symbol=Thin Cross|IsActive=T|SuppressAll=T
|RECORD=22|IndexInSheet=253|OwnerPartId=-1|Location.X=580|Location.Y=428|Color=255|Orientation=1|Symbol=Thin Cross|IsActive=T|SuppressAll=T
|RECORD=22|IndexInSheet=254|OwnerPartId=-1|Location.X=580|Location.Y=418|Color=255|Orientation=1|Symbol=Thin Cross|IsActive=T|SuppressAll=T
|RECORD=22|IndexInSheet=255|OwnerPartId=-1|Location.X=460|Location.Y=448|Color=255|Orientation=1|Symbol=Thin Cross|IsActive=T|SuppressAll=T
|RECORD=22|IndexInSheet=256|OwnerPartId=-1|Location.X=460|Location.Y=438|Color=255|Orientation=1|Symbol=Thin Cross|IsActive=T|SuppressAll=T
|RECORD=22|IndexInSheet=257|OwnerPartId=-1|Location.X=460|Location.Y=428|Color=255|Orientation=1|Symbol=Thin Cross|IsActive=T|SuppressAll=T
|RECORD=22|IndexInSheet=258|OwnerPartId=-1|Location.X=460|Location.Y=418|Color=255|Orientation=1|Symbol=Thin Cross|IsActive=T|SuppressAll=T
|RECORD=22|IndexInSheet=259|OwnerPartId=-1|Location.X=460|Location.Y=378|Color=255|Orientation=1|Symbol=Thin Cross|IsActive=T|SuppressAll=T
|RECORD=22|IndexInSheet=260|OwnerPartId=-1|Location.X=460|Location.Y=368|Color=255|Orientation=1|Symbol=Thin Cross|IsActive=T|SuppressAll=T
|RECORD=22|IndexInSheet=261|OwnerPartId=-1|Location.X=580|Location.Y=398|Color=255|Orientation=1|Symbol=Thin Cross|IsActive=T|SuppressAll=T
|RECORD=22|IndexInSheet=262|OwnerPartId=-1|Location.X=580|Location.Y=388|Color=255|Orientation=1|Symbol=Thin Cross|IsActive=T|SuppressAll=T
|RECORD=22|IndexInSheet=263|OwnerPartId=-1|Location.X=580|Location.Y=378|Color=255|Orientation=1|Symbol=Thin Cross|IsActive=T|SuppressAll=T
|RECORD=22|IndexInSheet=264|OwnerPartId=-1|Location.X=580|Location.Y=368|Color=255|Orientation=1|Symbol=Thin Cross|IsActive=T|SuppressAll=T
|RECORD=22|IndexInSheet=265|OwnerPartId=-1|Location.X=580|Location.Y=348|Color=255|Orientation=1|Symbol=Thin Cross|IsActive=T|SuppressAll=T
|RECORD=22|IndexInSheet=266|OwnerPartId=-1|Location.X=580|Location.Y=338|Color=255|Orientation=1|Symbol=Thin Cross|IsActive=T|SuppressAll=T
|RECORD=22|IndexInSheet=267|OwnerPartId=-1|Location.X=580|Location.Y=328|Color=255|Orientation=1|Symbol=Thin Cross|IsActive=T|SuppressAll=T
|RECORD=22|IndexInSheet=268|OwnerPartId=-1|Location.X=580|Location.Y=318|Color=255|Orientation=1|Symbol=Thin Cross|IsActive=T|SuppressAll=T
|RECORD=22|IndexInSheet=269|OwnerPartId=-1|Location.X=460|Location.Y=338|Color=255|Orientation=1|Symbol=Thin Cross|IsActive=T|SuppressAll=T
|RECORD=22|IndexInSheet=270|OwnerPartId=-1|Location.X=460|Location.Y=328|Color=255|Orientation=1|Symbol=Thin Cross|IsActive=T|SuppressAll=T
|RECORD=22|IndexInSheet=271|OwnerPartId=-1|Location.X=460|Location.Y=298|Color=255|Orientation=1|Symbol=Thin Cross|IsActive=T|SuppressAll=T
|RECORD=22|IndexInSheet=272|OwnerPartId=-1|Location.X=460|Location.Y=288|Color=255|Orientation=1|Symbol=Thin Cross|IsActive=T|SuppressAll=T
|RECORD=22|IndexInSheet=273|OwnerPartId=-1|Location.X=460|Location.Y=278|Color=255|Orientation=1|Symbol=Thin Cross|IsActive=T|SuppressAll=T
|RECORD=22|IndexInSheet=274|OwnerPartId=-1|Location.X=460|Location.Y=268|Color=255|Orientation=1|Symbol=Thin Cross|IsActive=T|SuppressAll=T
|RECORD=22|IndexInSheet=275|OwnerPartId=-1|Location.X=580|Location.Y=298|Color=255|Orientation=1|Symbol=Thin Cross|IsActive=T|SuppressAll=T
|RECORD=22|IndexInSheet=276|OwnerPartId=-1|Location.X=580|Location.Y=288|Color=255|Orientation=1|Symbol=Thin Cross|IsActive=T|SuppressAll=T
|RECORD=22|IndexInSheet=277|OwnerPartId=-1|Location.X=580|Location.Y=268|Color=255|Orientation=1|Symbol=Thin Cross|IsActive=T|SuppressAll=T
|RECORD=22|IndexInSheet=278|OwnerPartId=-1|Location.X=580|Location.Y=278|Color=255|Orientation=1|Symbol=Thin Cross|IsActive=T|SuppressAll=T
|RECORD=22|IndexInSheet=279|OwnerPartId=-1|Location.X=460|Location.Y=238|Color=255|Orientation=1|Symbol=Thin Cross|IsActive=T|SuppressAll=T
|RECORD=22|IndexInSheet=280|OwnerPartId=-1|Location.X=460|Location.Y=228|Color=255|Orientation=1|Symbol=Thin Cross|IsActive=T|SuppressAll=T
|RECORD=22|IndexInSheet=281|OwnerPartId=-1|Location.X=460|Location.Y=218|Color=255|Orientation=1|Symbol=Thin Cross|IsActive=T|SuppressAll=T
|RECORD=22|IndexInSheet=282|OwnerPartId=-1|Location.X=580|Location.Y=248|Color=255|Orientation=1|Symbol=Thin Cross|IsActive=T|SuppressAll=T
|RECORD=22|IndexInSheet=283|OwnerPartId=-1|Location.X=580|Location.Y=238|Color=255|Orientation=1|Symbol=Thin Cross|IsActive=T|SuppressAll=T
|RECORD=22|IndexInSheet=284|OwnerPartId=-1|Location.X=580|Location.Y=228|Color=255|Orientation=1|Symbol=Thin Cross|IsActive=T|SuppressAll=T
|RECORD=22|IndexInSheet=285|OwnerPartId=-1|Location.X=580|Location.Y=218|Color=255|Orientation=1|Symbol=Thin Cross|IsActive=T|SuppressAll=T
|RECORD=22|IndexInSheet=286|OwnerPartId=-1|Location.X=460|Location.Y=198|Color=255|Orientation=1|Symbol=Thin Cross|IsActive=T|SuppressAll=T
|RECORD=22|IndexInSheet=287|OwnerPartId=-1|Location.X=460|Location.Y=188|Color=255|Orientation=1|Symbol=Thin Cross|IsActive=T|SuppressAll=T
|RECORD=22|IndexInSheet=288|OwnerPartId=-1|Location.X=460|Location.Y=178|Color=255|Orientation=1|Symbol=Thin Cross|IsActive=T|SuppressAll=T
|RECORD=22|IndexInSheet=289|OwnerPartId=-1|Location.X=460|Location.Y=168|Color=255|Orientation=1|Symbol=Thin Cross|IsActive=T|SuppressAll=T
|RECORD=22|IndexInSheet=290|OwnerPartId=-1|Location.X=580|Location.Y=198|Color=255|Orientation=1|Symbol=Thin Cross|IsActive=T|SuppressAll=T
|RECORD=22|IndexInSheet=291|OwnerPartId=-1|Location.X=580|Location.Y=188|Color=255|Orientation=1|Symbol=Thin Cross|IsActive=T|SuppressAll=T
|RECORD=22|IndexInSheet=292|OwnerPartId=-1|Location.X=580|Location.Y=178|Color=255|Orientation=1|Symbol=Thin Cross|IsActive=T|SuppressAll=T
|RECORD=22|IndexInSheet=293|OwnerPartId=-1|Location.X=580|Location.Y=168|Color=255|Orientation=1|Symbol=Thin Cross|IsActive=T|SuppressAll=T
|RECORD=22|IndexInSheet=294|OwnerPartId=-1|Location.X=580|Location.Y=148|Color=255|Orientation=1|Symbol=Thin Cross|IsActive=T|SuppressAll=T
|RECORD=22|IndexInSheet=295|OwnerPartId=-1|Location.X=580|Location.Y=138|Color=255|Orientation=1|Symbol=Thin Cross|IsActive=T|SuppressAll=T
|RECORD=22|IndexInSheet=296|OwnerPartId=-1|Location.X=460|Location.Y=148|Color=255|Orientation=1|Symbol=Thin Cross|IsActive=T|SuppressAll=T
|RECORD=22|IndexInSheet=297|OwnerPartId=-1|Location.X=460|Location.Y=148|Color=255|Orientation=1|Symbol=Thin Cross|IsActive=T|SuppressAll=T
|RECORD=22|IndexInSheet=298|OwnerPartId=-1|Location.X=460|Location.Y=138|Color=255|Orientation=1|Symbol=Thin Cross|IsActive=T|SuppressAll=T
|RECORD=22|IndexInSheet=299|OwnerPartId=-1|Location.X=460|Location.Y=98|Color=255|Orientation=1|Symbol=Thin Cross|IsActive=T|SuppressAll=T
|RECORD=22|IndexInSheet=300|OwnerPartId=-1|Location.X=460|Location.Y=88|Color=255|Orientation=1|Symbol=Thin Cross|IsActive=T|SuppressAll=T
|RECORD=22|IndexInSheet=301|OwnerPartId=-1|Location.X=580|Location.Y=88|Color=255|Orientation=1|Symbol=Thin Cross|IsActive=T|SuppressAll=T
|RECORD=22|IndexInSheet=302|OwnerPartId=-1|Location.X=580|Location.Y=98|Color=255|Orientation=1|Symbol=Thin Cross|IsActive=T|SuppressAll=T
|RECORD=1|LibReference=FPGA_CONN|PartCount=5|DisplayModeCount=1|IndexInSheet=303|OwnerPartId=-1|Location.X=460|Location.Y=988|CurrentPartId=1|LibraryPath=*|SourceLibraryName=FPGA_CONN.SchLib|TargetFileName=*|AreaColor=11599871|Color=128|PartIDLocked=T|NotUseDBTableName=T|DesignItemId=FPGA_CONN|AllPinCount=336
|RECORD=14|OwnerIndex=332|IsNotAccesible=T|OwnerPartId=2|Location.X=490|Location.Y=568|Corner.X=550|Corner.Y=998|Color=128|AreaColor=11599871|IsSolid=T
|RECORD=2|OwnerIndex=332|OwnerPartId=2|FormalType=1|PinConglomerate=58|PinLength=30|Location.X=490|Location.Y=988|Name=1|Designator=B-1|PinPropagationDelay=0.000000E+000
|RECORD=2|OwnerIndex=332|OwnerPartId=2|FormalType=1|PinConglomerate=56|PinLength=30|Location.X=550|Location.Y=988|Name=2|Designator=B-2|PinPropagationDelay=0.000000E+000
|RECORD=2|OwnerIndex=332|OwnerPartId=2|FormalType=1|PinConglomerate=58|PinLength=30|Location.X=490|Location.Y=978|Name=3|Designator=B-3|PinPropagationDelay=0.000000E+000
|RECORD=2|OwnerIndex=332|OwnerPartId=2|FormalType=1|PinConglomerate=56|PinLength=30|Location.X=550|Location.Y=978|Name=4|Designator=B-4|PinPropagationDelay=0.000000E+000
|RECORD=2|OwnerIndex=332|OwnerPartId=2|FormalType=1|PinConglomerate=58|PinLength=30|Location.X=490|Location.Y=968|Name=5|Designator=B-5|PinPropagationDelay=0.000000E+000
|RECORD=2|OwnerIndex=332|OwnerPartId=2|FormalType=1|PinConglomerate=56|PinLength=30|Location.X=550|Location.Y=968|Name=6|Designator=B-6|PinPropagationDelay=0.000000E+000
|RECORD=2|OwnerIndex=332|OwnerPartId=2|FormalType=1|PinConglomerate=58|PinLength=30|Location.X=490|Location.Y=958|Name=7|Designator=B-7|PinPropagationDelay=0.000000E+000
|RECORD=2|OwnerIndex=332|OwnerPartId=2|FormalType=1|PinConglomerate=56|PinLength=30|Location.X=550|Location.Y=958|Name=8|Designator=B-8|PinPropagationDelay=0.000000E+000
|RECORD=2|OwnerIndex=332|OwnerPartId=2|FormalType=1|PinConglomerate=58|PinLength=30|Location.X=490|Location.Y=948|Name=9|Designator=B-9|PinPropagationDelay=0.000000E+000
|RECORD=2|OwnerIndex=332|OwnerPartId=2|FormalType=1|PinConglomerate=56|PinLength=30|Location.X=550|Location.Y=948|Name=10|Designator=B-10|PinPropagationDelay=0.000000E+000
|RECORD=2|OwnerIndex=332|OwnerPartId=2|FormalType=1|PinConglomerate=58|PinLength=30|Location.X=490|Location.Y=938|Name=11|Designator=B-11|PinPropagationDelay=0.000000E+000
|RECORD=2|OwnerIndex=332|OwnerPartId=2|FormalType=1|PinConglomerate=56|PinLength=30|Location.X=550|Location.Y=938|Name=12|Designator=B-12|PinPropagationDelay=0.000000E+000
|RECORD=2|OwnerIndex=332|OwnerPartId=2|FormalType=1|PinConglomerate=58|PinLength=30|Location.X=490|Location.Y=928|Name=13|Designator=B-13|PinPropagationDelay=0.000000E+000
|RECORD=2|OwnerIndex=332|OwnerPartId=2|FormalType=1|PinConglomerate=56|PinLength=30|Location.X=550|Location.Y=928|Name=14|Designator=B-14|PinPropagationDelay=0.000000E+000
|RECORD=2|OwnerIndex=332|OwnerPartId=2|FormalType=1|PinConglomerate=58|PinLength=30|Location.X=490|Location.Y=918|Name=15|Designator=B-15|PinPropagationDelay=0.000000E+000
|RECORD=2|OwnerIndex=332|OwnerPartId=2|FormalType=1|PinConglomerate=56|PinLength=30|Location.X=550|Location.Y=918|Name=16|Designator=B-16|PinPropagationDelay=0.000000E+000
|RECORD=2|OwnerIndex=332|OwnerPartId=2|FormalType=1|PinConglomerate=58|PinLength=30|Location.X=490|Location.Y=908|Name=17|Designator=B-17|PinPropagationDelay=0.000000E+000
|RECORD=2|OwnerIndex=332|OwnerPartId=2|FormalType=1|PinConglomerate=56|PinLength=30|Location.X=550|Location.Y=908|Name=18|Designator=B-18|PinPropagationDelay=0.000000E+000
|RECORD=2|OwnerIndex=332|OwnerPartId=2|FormalType=1|PinConglomerate=58|PinLength=30|Location.X=490|Location.Y=898|Name=19|Designator=B-19|PinPropagationDelay=0.000000E+000
|RECORD=2|OwnerIndex=332|OwnerPartId=2|FormalType=1|PinConglomerate=56|PinLength=30|Location.X=550|Location.Y=898|Name=20|Designator=B-20|PinPropagationDelay=0.000000E+000
|RECORD=2|OwnerIndex=332|OwnerPartId=2|FormalType=1|PinConglomerate=58|PinLength=30|Location.X=490|Location.Y=888|Name=21|Designator=B-21|PinPropagationDelay=0.000000E+000
|RECORD=2|OwnerIndex=332|OwnerPartId=2|FormalType=1|PinConglomerate=56|PinLength=30|Location.X=550|Location.Y=888|Name=22|Designator=B-22|PinPropagationDelay=0.000000E+000
|RECORD=2|OwnerIndex=332|OwnerPartId=2|FormalType=1|PinConglomerate=58|PinLength=30|Location.X=490|Location.Y=878|Name=23|Designator=B-23|PinPropagationDelay=0.000000E+000
|RECORD=2|OwnerIndex=332|OwnerPartId=2|FormalType=1|PinConglomerate=56|PinLength=30|Location.X=550|Location.Y=878|Name=24|Designator=B-24|PinPropagationDelay=0.000000E+000
|RECORD=2|OwnerIndex=332|OwnerPartId=2|FormalType=1|PinConglomerate=58|PinLength=30|Location.X=490|Location.Y=868|Name=25|Designator=B-25|PinPropagationDelay=0.000000E+000
|RECORD=2|OwnerIndex=332|OwnerPartId=2|FormalType=1|PinConglomerate=56|PinLength=30|Location.X=550|Location.Y=868|Name=26|Designator=B-26|PinPropagationDelay=0.000000E+000
|RECORD=2|OwnerIndex=332|OwnerPartId=2|FormalType=1|PinConglomerate=58|PinLength=30|Location.X=490|Location.Y=858|Name=27|Designator=B-27|PinPropagationDelay=0.000000E+000
|RECORD=2|OwnerIndex=332|OwnerPartId=2|FormalType=1|PinConglomerate=56|PinLength=30|Location.X=550|Location.Y=858|Name=28|Designator=B-28|PinPropagationDelay=0.000000E+000
|RECORD=2|OwnerIndex=332|OwnerPartId=2|FormalType=1|PinConglomerate=58|PinLength=30|Location.X=490|Location.Y=848|Name=29|Designator=B-29|PinPropagationDelay=0.000000E+000
|RECORD=2|OwnerIndex=332|OwnerPartId=2|FormalType=1|PinConglomerate=56|PinLength=30|Location.X=550|Location.Y=848|Name=30|Designator=B-30|PinPropagationDelay=0.000000E+000
|RECORD=2|OwnerIndex=332|OwnerPartId=2|FormalType=1|PinConglomerate=58|PinLength=30|Location.X=490|Location.Y=838|Name=31|Designator=B-31|PinPropagationDelay=0.000000E+000
|RECORD=2|OwnerIndex=332|OwnerPartId=2|FormalType=1|PinConglomerate=56|PinLength=30|Location.X=550|Location.Y=838|Name=32|Designator=B-32|PinPropagationDelay=0.000000E+000
|RECORD=2|OwnerIndex=332|OwnerPartId=2|FormalType=1|PinConglomerate=58|PinLength=30|Location.X=490|Location.Y=828|Name=33|Designator=B-33|PinPropagationDelay=0.000000E+000
|RECORD=2|OwnerIndex=332|OwnerPartId=2|FormalType=1|PinConglomerate=56|PinLength=30|Location.X=550|Location.Y=828|Name=34|Designator=B-34|PinPropagationDelay=0.000000E+000
|RECORD=2|OwnerIndex=332|OwnerPartId=2|FormalType=1|PinConglomerate=58|PinLength=30|Location.X=490|Location.Y=818|Name=35|Designator=B-35|PinPropagationDelay=0.000000E+000
|RECORD=2|OwnerIndex=332|OwnerPartId=2|FormalType=1|PinConglomerate=56|PinLength=30|Location.X=550|Location.Y=818|Name=36|Designator=B-36|PinPropagationDelay=0.000000E+000
|RECORD=2|OwnerIndex=332|OwnerPartId=2|FormalType=1|PinConglomerate=58|PinLength=30|Location.X=490|Location.Y=808|Name=37|Designator=B-37|PinPropagationDelay=0.000000E+000
|RECORD=2|OwnerIndex=332|OwnerPartId=2|FormalType=1|PinConglomerate=56|PinLength=30|Location.X=550|Location.Y=808|Name=38|Designator=B-38|PinPropagationDelay=0.000000E+000
|RECORD=2|OwnerIndex=332|OwnerPartId=2|FormalType=1|PinConglomerate=58|PinLength=30|Location.X=490|Location.Y=798|Name=39|Designator=B-39|PinPropagationDelay=0.000000E+000
|RECORD=2|OwnerIndex=332|OwnerPartId=2|FormalType=1|PinConglomerate=56|PinLength=30|Location.X=550|Location.Y=798|Name=40|Designator=B-40|PinPropagationDelay=0.000000E+000
|RECORD=2|OwnerIndex=332|OwnerPartId=2|FormalType=1|PinConglomerate=58|PinLength=30|Location.X=490|Location.Y=788|Name=41|Designator=B-41|PinPropagationDelay=0.000000E+000
|RECORD=2|OwnerIndex=332|OwnerPartId=2|FormalType=1|PinConglomerate=56|PinLength=30|Location.X=550|Location.Y=788|Name=42|Designator=B-42|PinPropagationDelay=0.000000E+000
|RECORD=2|OwnerIndex=332|OwnerPartId=2|FormalType=1|PinConglomerate=58|PinLength=30|Location.X=490|Location.Y=778|Name=43|Designator=B-43|PinPropagationDelay=0.000000E+000
|RECORD=2|OwnerIndex=332|OwnerPartId=2|FormalType=1|PinConglomerate=56|PinLength=30|Location.X=550|Location.Y=778|Name=44|Designator=B-44|PinPropagationDelay=0.000000E+000
|RECORD=2|OwnerIndex=332|OwnerPartId=2|FormalType=1|PinConglomerate=58|PinLength=30|Location.X=490|Location.Y=768|Name=45|Designator=B-45|PinPropagationDelay=0.000000E+000
|RECORD=2|OwnerIndex=332|OwnerPartId=2|FormalType=1|PinConglomerate=56|PinLength=30|Location.X=550|Location.Y=768|Name=46|Designator=B-46|PinPropagationDelay=0.000000E+000
|RECORD=2|OwnerIndex=332|OwnerPartId=2|FormalType=1|PinConglomerate=58|PinLength=30|Location.X=490|Location.Y=758|Name=47|Designator=B-47|PinPropagationDelay=0.000000E+000
|RECORD=2|OwnerIndex=332|OwnerPartId=2|FormalType=1|PinConglomerate=56|PinLength=30|Location.X=550|Location.Y=758|Name=48|Designator=B-48|PinPropagationDelay=0.000000E+000
|RECORD=2|OwnerIndex=332|OwnerPartId=2|FormalType=1|PinConglomerate=58|PinLength=30|Location.X=490|Location.Y=748|Name=49|Designator=B-49|PinPropagationDelay=0.000000E+000
|RECORD=2|OwnerIndex=332|OwnerPartId=2|FormalType=1|PinConglomerate=56|PinLength=30|Location.X=550|Location.Y=748|Name=50|Designator=B-50|PinPropagationDelay=0.000000E+000
|RECORD=2|OwnerIndex=332|OwnerPartId=2|FormalType=1|PinConglomerate=58|PinLength=30|Location.X=490|Location.Y=738|Name=51|Designator=B-51|PinPropagationDelay=0.000000E+000
|RECORD=2|OwnerIndex=332|OwnerPartId=2|FormalType=1|PinConglomerate=56|PinLength=30|Location.X=550|Location.Y=738|Name=52|Designator=B-52|PinPropagationDelay=0.000000E+000
|RECORD=2|OwnerIndex=332|OwnerPartId=2|FormalType=1|PinConglomerate=58|PinLength=30|Location.X=490|Location.Y=728|Name=53|Designator=B-53|PinPropagationDelay=0.000000E+000
|RECORD=2|OwnerIndex=332|OwnerPartId=2|FormalType=1|PinConglomerate=56|PinLength=30|Location.X=550|Location.Y=728|Name=54|Designator=B-54|PinPropagationDelay=0.000000E+000
|RECORD=2|OwnerIndex=332|OwnerPartId=2|FormalType=1|PinConglomerate=58|PinLength=30|Location.X=490|Location.Y=718|Name=55|Designator=B-55|PinPropagationDelay=0.000000E+000
|RECORD=2|OwnerIndex=332|OwnerPartId=2|FormalType=1|PinConglomerate=56|PinLength=30|Location.X=550|Location.Y=718|Name=56|Designator=B-56|PinPropagationDelay=0.000000E+000
|RECORD=2|OwnerIndex=332|OwnerPartId=2|FormalType=1|PinConglomerate=58|PinLength=30|Location.X=490|Location.Y=708|Name=57|Designator=B-57|PinPropagationDelay=0.000000E+000
|RECORD=2|OwnerIndex=332|OwnerPartId=2|FormalType=1|PinConglomerate=56|PinLength=30|Location.X=550|Location.Y=708|Name=58|Designator=B-58|PinPropagationDelay=0.000000E+000
|RECORD=2|OwnerIndex=332|OwnerPartId=2|FormalType=1|PinConglomerate=58|PinLength=30|Location.X=490|Location.Y=698|Name=59|Designator=B-59|PinPropagationDelay=0.000000E+000
|RECORD=2|OwnerIndex=332|OwnerPartId=2|FormalType=1|PinConglomerate=56|PinLength=30|Location.X=550|Location.Y=698|Name=60|Designator=B-60|PinPropagationDelay=0.000000E+000
|RECORD=2|OwnerIndex=332|OwnerPartId=2|FormalType=1|PinConglomerate=58|PinLength=30|Location.X=490|Location.Y=688|Name=61|Designator=B-61|PinPropagationDelay=0.000000E+000
|RECORD=2|OwnerIndex=332|OwnerPartId=2|FormalType=1|PinConglomerate=56|PinLength=30|Location.X=550|Location.Y=688|Name=62|Designator=B-62|PinPropagationDelay=0.000000E+000
|RECORD=2|OwnerIndex=332|OwnerPartId=2|FormalType=1|PinConglomerate=58|PinLength=30|Location.X=490|Location.Y=678|Name=63|Designator=B-63|PinPropagationDelay=0.000000E+000
|RECORD=2|OwnerIndex=332|OwnerPartId=2|FormalType=1|PinConglomerate=56|PinLength=30|Location.X=550|Location.Y=678|Name=64|Designator=B-64|PinPropagationDelay=0.000000E+000
|RECORD=2|OwnerIndex=332|OwnerPartId=2|FormalType=1|PinConglomerate=58|PinLength=30|Location.X=490|Location.Y=668|Name=65|Designator=B-65|PinPropagationDelay=0.000000E+000
|RECORD=2|OwnerIndex=332|OwnerPartId=2|FormalType=1|PinConglomerate=56|PinLength=30|Location.X=550|Location.Y=668|Name=66|Designator=B-66|PinPropagationDelay=0.000000E+000
|RECORD=2|OwnerIndex=332|OwnerPartId=2|FormalType=1|PinConglomerate=58|PinLength=30|Location.X=490|Location.Y=658|Name=67|Designator=B-67|PinPropagationDelay=0.000000E+000
|RECORD=2|OwnerIndex=332|OwnerPartId=2|FormalType=1|PinConglomerate=56|PinLength=30|Location.X=550|Location.Y=658|Name=68|Designator=B-68|PinPropagationDelay=0.000000E+000
|RECORD=2|OwnerIndex=332|OwnerPartId=2|FormalType=1|PinConglomerate=58|PinLength=30|Location.X=490|Location.Y=648|Name=69|Designator=B-69|PinPropagationDelay=0.000000E+000
|RECORD=2|OwnerIndex=332|OwnerPartId=2|FormalType=1|PinConglomerate=56|PinLength=30|Location.X=550|Location.Y=648|Name=70|Designator=B-70|PinPropagationDelay=0.000000E+000
|RECORD=2|OwnerIndex=332|OwnerPartId=2|FormalType=1|PinConglomerate=58|PinLength=30|Location.X=490|Location.Y=638|Name=71|Designator=B-71|PinPropagationDelay=0.000000E+000
|RECORD=2|OwnerIndex=332|OwnerPartId=2|FormalType=1|PinConglomerate=56|PinLength=30|Location.X=550|Location.Y=638|Name=72|Designator=B-72|PinPropagationDelay=0.000000E+000
|RECORD=2|OwnerIndex=332|OwnerPartId=2|FormalType=1|PinConglomerate=58|PinLength=30|Location.X=490|Location.Y=628|Name=73|Designator=B-73|PinPropagationDelay=0.000000E+000
|RECORD=2|OwnerIndex=332|OwnerPartId=2|FormalType=1|PinConglomerate=56|PinLength=30|Location.X=550|Location.Y=628|Name=74|Designator=B-74|PinPropagationDelay=0.000000E+000
|RECORD=2|OwnerIndex=332|OwnerPartId=2|FormalType=1|PinConglomerate=58|PinLength=30|Location.X=490|Location.Y=618|Name=75|Designator=B-75|PinPropagationDelay=0.000000E+000
|RECORD=2|OwnerIndex=332|OwnerPartId=2|FormalType=1|PinConglomerate=56|PinLength=30|Location.X=550|Location.Y=618|Name=76|Designator=B-76|PinPropagationDelay=0.000000E+000
|RECORD=2|OwnerIndex=332|OwnerPartId=2|FormalType=1|PinConglomerate=58|PinLength=30|Location.X=490|Location.Y=608|Name=77|Designator=B-77|PinPropagationDelay=0.000000E+000
|RECORD=2|OwnerIndex=332|OwnerPartId=2|FormalType=1|PinConglomerate=56|PinLength=30|Location.X=550|Location.Y=608|Name=78|Designator=B-78|PinPropagationDelay=0.000000E+000
|RECORD=2|OwnerIndex=332|OwnerPartId=2|FormalType=1|PinConglomerate=58|PinLength=30|Location.X=490|Location.Y=598|Name=79|Designator=B-79|PinPropagationDelay=0.000000E+000
|RECORD=2|OwnerIndex=332|OwnerPartId=2|FormalType=1|PinConglomerate=56|PinLength=30|Location.X=550|Location.Y=598|Name=80|Designator=B-80|PinPropagationDelay=0.000000E+000
|RECORD=2|OwnerIndex=332|OwnerPartId=2|FormalType=1|PinConglomerate=58|PinLength=30|Location.X=490|Location.Y=588|Name=81|Designator=B-81|PinPropagationDelay=0.000000E+000
|RECORD=2|OwnerIndex=332|OwnerPartId=2|FormalType=1|PinConglomerate=56|PinLength=30|Location.X=550|Location.Y=588|Name=82|Designator=B-82|PinPropagationDelay=0.000000E+000
|RECORD=2|OwnerIndex=332|OwnerPartId=2|FormalType=1|PinConglomerate=58|PinLength=30|Location.X=490|Location.Y=578|Name=83|Designator=B-83|PinPropagationDelay=0.000000E+000
|RECORD=2|OwnerIndex=332|OwnerPartId=2|FormalType=1|PinConglomerate=56|PinLength=30|Location.X=550|Location.Y=578|Name=84|Designator=B-84|PinPropagationDelay=0.000000E+000
|RECORD=14|OwnerIndex=332|IsNotAccesible=T|IndexInSheet=85|OwnerPartId=3|Location.X=490|Location.Y=568|Corner.X=550|Corner.Y=998|Color=128|AreaColor=11599871|IsSolid=T
|RECORD=2|OwnerIndex=332|OwnerPartId=3|FormalType=1|PinConglomerate=58|PinLength=30|Location.X=490|Location.Y=988|Name=1|Designator=C-1|PinPropagationDelay=0.000000E+000
|RECORD=2|OwnerIndex=332|OwnerPartId=3|FormalType=1|PinConglomerate=56|PinLength=30|Location.X=550|Location.Y=988|Name=2|Designator=C-2|PinPropagationDelay=0.000000E+000
|RECORD=2|OwnerIndex=332|OwnerPartId=3|FormalType=1|PinConglomerate=58|PinLength=30|Location.X=490|Location.Y=978|Name=3|Designator=C-3|PinPropagationDelay=0.000000E+000
|RECORD=2|OwnerIndex=332|OwnerPartId=3|FormalType=1|PinConglomerate=56|PinLength=30|Location.X=550|Location.Y=978|Name=4|Designator=C-4|PinPropagationDelay=0.000000E+000
|RECORD=2|OwnerIndex=332|OwnerPartId=3|FormalType=1|PinConglomerate=58|PinLength=30|Location.X=490|Location.Y=968|Name=5|Designator=C-5|PinPropagationDelay=0.000000E+000
|RECORD=2|OwnerIndex=332|OwnerPartId=3|FormalType=1|PinConglomerate=56|PinLength=30|Location.X=550|Location.Y=968|Name=6|Designator=C-6|PinPropagationDelay=0.000000E+000
|RECORD=2|OwnerIndex=332|OwnerPartId=3|FormalType=1|PinConglomerate=58|PinLength=30|Location.X=490|Location.Y=958|Name=7|Designator=C-7|PinPropagationDelay=0.000000E+000
|RECORD=2|OwnerIndex=332|OwnerPartId=3|FormalType=1|PinConglomerate=56|PinLength=30|Location.X=550|Location.Y=958|Name=8|Designator=C-8|PinPropagationDelay=0.000000E+000
|RECORD=2|OwnerIndex=332|OwnerPartId=3|FormalType=1|PinConglomerate=58|PinLength=30|Location.X=490|Location.Y=948|Name=9|Designator=C-9|PinPropagationDelay=0.000000E+000
|RECORD=2|OwnerIndex=332|OwnerPartId=3|FormalType=1|PinConglomerate=56|PinLength=30|Location.X=550|Location.Y=948|Name=10|Designator=C-10|PinPropagationDelay=0.000000E+000
|RECORD=2|OwnerIndex=332|OwnerPartId=3|FormalType=1|PinConglomerate=58|PinLength=30|Location.X=490|Location.Y=938|Name=11|Designator=C-11|PinPropagationDelay=0.000000E+000
|RECORD=2|OwnerIndex=332|OwnerPartId=3|FormalType=1|PinConglomerate=56|PinLength=30|Location.X=550|Location.Y=938|Name=12|Designator=C-12|PinPropagationDelay=0.000000E+000
|RECORD=2|OwnerIndex=332|OwnerPartId=3|FormalType=1|PinConglomerate=58|PinLength=30|Location.X=490|Location.Y=928|Name=13|Designator=C-13|PinPropagationDelay=0.000000E+000
|RECORD=2|OwnerIndex=332|OwnerPartId=3|FormalType=1|PinConglomerate=56|PinLength=30|Location.X=550|Location.Y=928|Name=14|Designator=C-14|PinPropagationDelay=0.000000E+000
|RECORD=2|OwnerIndex=332|OwnerPartId=3|FormalType=1|PinConglomerate=58|PinLength=30|Location.X=490|Location.Y=918|Name=15|Designator=C-15|PinPropagationDelay=0.000000E+000
|RECORD=2|OwnerIndex=332|OwnerPartId=3|FormalType=1|PinConglomerate=56|PinLength=30|Location.X=550|Location.Y=918|Name=16|Designator=C-16|PinPropagationDelay=0.000000E+000
|RECORD=2|OwnerIndex=332|OwnerPartId=3|FormalType=1|PinConglomerate=58|PinLength=30|Location.X=490|Location.Y=908|Name=17|Designator=C-17|PinPropagationDelay=0.000000E+000
|RECORD=2|OwnerIndex=332|OwnerPartId=3|FormalType=1|PinConglomerate=56|PinLength=30|Location.X=550|Location.Y=908|Name=18|Designator=C-18|PinPropagationDelay=0.000000E+000
|RECORD=2|OwnerIndex=332|OwnerPartId=3|FormalType=1|PinConglomerate=58|PinLength=30|Location.X=490|Location.Y=898|Name=19|Designator=C-19|PinPropagationDelay=0.000000E+000
|RECORD=2|OwnerIndex=332|OwnerPartId=3|FormalType=1|PinConglomerate=56|PinLength=30|Location.X=550|Location.Y=898|Name=20|Designator=C-20|PinPropagationDelay=0.000000E+000
|RECORD=2|OwnerIndex=332|OwnerPartId=3|FormalType=1|PinConglomerate=58|PinLength=30|Location.X=490|Location.Y=888|Name=21|Designator=C-21|PinPropagationDelay=0.000000E+000
|RECORD=2|OwnerIndex=332|OwnerPartId=3|FormalType=1|PinConglomerate=56|PinLength=30|Location.X=550|Location.Y=888|Name=22|Designator=C-22|PinPropagationDelay=0.000000E+000
|RECORD=2|OwnerIndex=332|OwnerPartId=3|FormalType=1|PinConglomerate=58|PinLength=30|Location.X=490|Location.Y=878|Name=23|Designator=C-23|PinPropagationDelay=0.000000E+000
|RECORD=2|OwnerIndex=332|OwnerPartId=3|FormalType=1|PinConglomerate=56|PinLength=30|Location.X=550|Location.Y=878|Name=24|Designator=C-24|PinPropagationDelay=0.000000E+000
|RECORD=2|OwnerIndex=332|OwnerPartId=3|FormalType=1|PinConglomerate=58|PinLength=30|Location.X=490|Location.Y=868|Name=25|Designator=C-25|PinPropagationDelay=0.000000E+000
|RECORD=2|OwnerIndex=332|OwnerPartId=3|FormalType=1|PinConglomerate=56|PinLength=30|Location.X=550|Location.Y=868|Name=26|Designator=C-26|PinPropagationDelay=0.000000E+000
|RECORD=2|OwnerIndex=332|OwnerPartId=3|FormalType=1|PinConglomerate=58|PinLength=30|Location.X=490|Location.Y=858|Name=27|Designator=C-27|PinPropagationDelay=0.000000E+000
|RECORD=2|OwnerIndex=332|OwnerPartId=3|FormalType=1|PinConglomerate=56|PinLength=30|Location.X=550|Location.Y=858|Name=28|Designator=C-28|PinPropagationDelay=0.000000E+000
|RECORD=2|OwnerIndex=332|OwnerPartId=3|FormalType=1|PinConglomerate=58|PinLength=30|Location.X=490|Location.Y=848|Name=29|Designator=C-29|PinPropagationDelay=0.000000E+000
|RECORD=2|OwnerIndex=332|OwnerPartId=3|FormalType=1|PinConglomerate=56|PinLength=30|Location.X=550|Location.Y=848|Name=30|Designator=C-30|PinPropagationDelay=0.000000E+000
|RECORD=2|OwnerIndex=332|OwnerPartId=3|FormalType=1|PinConglomerate=58|PinLength=30|Location.X=490|Location.Y=838|Name=31|Designator=C-31|PinPropagationDelay=0.000000E+000
|RECORD=2|OwnerIndex=332|OwnerPartId=3|FormalType=1|PinConglomerate=56|PinLength=30|Location.X=550|Location.Y=838|Name=32|Designator=C-32|PinPropagationDelay=0.000000E+000
|RECORD=2|OwnerIndex=332|OwnerPartId=3|FormalType=1|PinConglomerate=58|PinLength=30|Location.X=490|Location.Y=828|Name=33|Designator=C-33|PinPropagationDelay=0.000000E+000
|RECORD=2|OwnerIndex=332|OwnerPartId=3|FormalType=1|PinConglomerate=56|PinLength=30|Location.X=550|Location.Y=828|Name=34|Designator=C-34|PinPropagationDelay=0.000000E+000
|RECORD=2|OwnerIndex=332|OwnerPartId=3|FormalType=1|PinConglomerate=58|PinLength=30|Location.X=490|Location.Y=818|Name=35|Designator=C-35|PinPropagationDelay=0.000000E+000
|RECORD=2|OwnerIndex=332|OwnerPartId=3|FormalType=1|PinConglomerate=56|PinLength=30|Location.X=550|Location.Y=818|Name=36|Designator=C-36|PinPropagationDelay=0.000000E+000
|RECORD=2|OwnerIndex=332|OwnerPartId=3|FormalType=1|PinConglomerate=58|PinLength=30|Location.X=490|Location.Y=808|Name=37|Designator=C-37|PinPropagationDelay=0.000000E+000
|RECORD=2|OwnerIndex=332|OwnerPartId=3|FormalType=1|PinConglomerate=56|PinLength=30|Location.X=550|Location.Y=808|Name=38|Designator=C-38|PinPropagationDelay=0.000000E+000
|RECORD=2|OwnerIndex=332|OwnerPartId=3|FormalType=1|PinConglomerate=58|PinLength=30|Location.X=490|Location.Y=798|Name=39|Designator=C-39|PinPropagationDelay=0.000000E+000
|RECORD=2|OwnerIndex=332|OwnerPartId=3|FormalType=1|PinConglomerate=56|PinLength=30|Location.X=550|Location.Y=798|Name=40|Designator=C-40|PinPropagationDelay=0.000000E+000
|RECORD=2|OwnerIndex=332|OwnerPartId=3|FormalType=1|PinConglomerate=58|PinLength=30|Location.X=490|Location.Y=788|Name=41|Designator=C-41|PinPropagationDelay=0.000000E+000
|RECORD=2|OwnerIndex=332|OwnerPartId=3|FormalType=1|PinConglomerate=56|PinLength=30|Location.X=550|Location.Y=788|Name=42|Designator=C-42|PinPropagationDelay=0.000000E+000
|RECORD=2|OwnerIndex=332|OwnerPartId=3|FormalType=1|PinConglomerate=58|PinLength=30|Location.X=490|Location.Y=778|Name=43|Designator=C-43|PinPropagationDelay=0.000000E+000
|RECORD=2|OwnerIndex=332|OwnerPartId=3|FormalType=1|PinConglomerate=56|PinLength=30|Location.X=550|Location.Y=778|Name=44|Designator=C-44|PinPropagationDelay=0.000000E+000
|RECORD=2|OwnerIndex=332|OwnerPartId=3|FormalType=1|PinConglomerate=58|PinLength=30|Location.X=490|Location.Y=768|Name=45|Designator=C-45|PinPropagationDelay=0.000000E+000
|RECORD=2|OwnerIndex=332|OwnerPartId=3|FormalType=1|PinConglomerate=56|PinLength=30|Location.X=550|Location.Y=768|Name=46|Designator=C-46|PinPropagationDelay=0.000000E+000
|RECORD=2|OwnerIndex=332|OwnerPartId=3|FormalType=1|PinConglomerate=58|PinLength=30|Location.X=490|Location.Y=758|Name=47|Designator=C-47|PinPropagationDelay=0.000000E+000
|RECORD=2|OwnerIndex=332|OwnerPartId=3|FormalType=1|PinConglomerate=56|PinLength=30|Location.X=550|Location.Y=758|Name=48|Designator=C-48|PinPropagationDelay=0.000000E+000
|RECORD=2|OwnerIndex=332|OwnerPartId=3|FormalType=1|PinConglomerate=58|PinLength=30|Location.X=490|Location.Y=748|Name=49|Designator=C-49|PinPropagationDelay=0.000000E+000
|RECORD=2|OwnerIndex=332|OwnerPartId=3|FormalType=1|PinConglomerate=56|PinLength=30|Location.X=550|Location.Y=748|Name=50|Designator=C-50|PinPropagationDelay=0.000000E+000
|RECORD=2|OwnerIndex=332|OwnerPartId=3|FormalType=1|PinConglomerate=58|PinLength=30|Location.X=490|Location.Y=738|Name=51|Designator=C-51|PinPropagationDelay=0.000000E+000
|RECORD=2|OwnerIndex=332|OwnerPartId=3|FormalType=1|PinConglomerate=56|PinLength=30|Location.X=550|Location.Y=738|Name=52|Designator=C-52|PinPropagationDelay=0.000000E+000
|RECORD=2|OwnerIndex=332|OwnerPartId=3|FormalType=1|PinConglomerate=58|PinLength=30|Location.X=490|Location.Y=728|Name=53|Designator=C-53|PinPropagationDelay=0.000000E+000
|RECORD=2|OwnerIndex=332|OwnerPartId=3|FormalType=1|PinConglomerate=56|PinLength=30|Location.X=550|Location.Y=728|Name=54|Designator=C-54|PinPropagationDelay=0.000000E+000
|RECORD=2|OwnerIndex=332|OwnerPartId=3|FormalType=1|PinConglomerate=58|PinLength=30|Location.X=490|Location.Y=718|Name=55|Designator=C-55|PinPropagationDelay=0.000000E+000
|RECORD=2|OwnerIndex=332|OwnerPartId=3|FormalType=1|PinConglomerate=56|PinLength=30|Location.X=550|Location.Y=718|Name=56|Designator=C-56|PinPropagationDelay=0.000000E+000
|RECORD=2|OwnerIndex=332|OwnerPartId=3|FormalType=1|PinConglomerate=58|PinLength=30|Location.X=490|Location.Y=708|Name=57|Designator=C-57|PinPropagationDelay=0.000000E+000
|RECORD=2|OwnerIndex=332|OwnerPartId=3|FormalType=1|PinConglomerate=56|PinLength=30|Location.X=550|Location.Y=708|Name=58|Designator=C-58|PinPropagationDelay=0.000000E+000
|RECORD=2|OwnerIndex=332|OwnerPartId=3|FormalType=1|PinConglomerate=58|PinLength=30|Location.X=490|Location.Y=698|Name=59|Designator=C-59|PinPropagationDelay=0.000000E+000
|RECORD=2|OwnerIndex=332|OwnerPartId=3|FormalType=1|PinConglomerate=56|PinLength=30|Location.X=550|Location.Y=698|Name=60|Designator=C-60|PinPropagationDelay=0.000000E+000
|RECORD=2|OwnerIndex=332|OwnerPartId=3|FormalType=1|PinConglomerate=58|PinLength=30|Location.X=490|Location.Y=688|Name=61|Designator=C-61|PinPropagationDelay=0.000000E+000
|RECORD=2|OwnerIndex=332|OwnerPartId=3|FormalType=1|PinConglomerate=56|PinLength=30|Location.X=550|Location.Y=688|Name=62|Designator=C-62|PinPropagationDelay=0.000000E+000
|RECORD=2|OwnerIndex=332|OwnerPartId=3|FormalType=1|PinConglomerate=58|PinLength=30|Location.X=490|Location.Y=678|Name=63|Designator=C-63|PinPropagationDelay=0.000000E+000
|RECORD=2|OwnerIndex=332|OwnerPartId=3|FormalType=1|PinConglomerate=56|PinLength=30|Location.X=550|Location.Y=678|Name=64|Designator=C-64|PinPropagationDelay=0.000000E+000
|RECORD=2|OwnerIndex=332|OwnerPartId=3|FormalType=1|PinConglomerate=58|PinLength=30|Location.X=490|Location.Y=668|Name=65|Designator=C-65|PinPropagationDelay=0.000000E+000
|RECORD=2|OwnerIndex=332|OwnerPartId=3|FormalType=1|PinConglomerate=56|PinLength=30|Location.X=550|Location.Y=668|Name=66|Designator=C-66|PinPropagationDelay=0.000000E+000
|RECORD=2|OwnerIndex=332|OwnerPartId=3|FormalType=1|PinConglomerate=58|PinLength=30|Location.X=490|Location.Y=658|Name=67|Designator=C-67|PinPropagationDelay=0.000000E+000
|RECORD=2|OwnerIndex=332|OwnerPartId=3|FormalType=1|PinConglomerate=56|PinLength=30|Location.X=550|Location.Y=658|Name=68|Designator=C-68|PinPropagationDelay=0.000000E+000
|RECORD=2|OwnerIndex=332|OwnerPartId=3|FormalType=1|PinConglomerate=58|PinLength=30|Location.X=490|Location.Y=648|Name=69|Designator=C-69|PinPropagationDelay=0.000000E+000
|RECORD=2|OwnerIndex=332|OwnerPartId=3|FormalType=1|PinConglomerate=56|PinLength=30|Location.X=550|Location.Y=648|Name=70|Designator=C-70|PinPropagationDelay=0.000000E+000
|RECORD=2|OwnerIndex=332|OwnerPartId=3|FormalType=1|PinConglomerate=58|PinLength=30|Location.X=490|Location.Y=638|Name=71|Designator=C-71|PinPropagationDelay=0.000000E+000
|RECORD=2|OwnerIndex=332|OwnerPartId=3|FormalType=1|PinConglomerate=56|PinLength=30|Location.X=550|Location.Y=638|Name=72|Designator=C-72|PinPropagationDelay=0.000000E+000
|RECORD=2|OwnerIndex=332|OwnerPartId=3|FormalType=1|PinConglomerate=58|PinLength=30|Location.X=490|Location.Y=628|Name=73|Designator=C-73|PinPropagationDelay=0.000000E+000
|RECORD=2|OwnerIndex=332|OwnerPartId=3|FormalType=1|PinConglomerate=56|PinLength=30|Location.X=550|Location.Y=628|Name=74|Designator=C-74|PinPropagationDelay=0.000000E+000
|RECORD=2|OwnerIndex=332|OwnerPartId=3|FormalType=1|PinConglomerate=58|PinLength=30|Location.X=490|Location.Y=618|Name=75|Designator=C-75|PinPropagationDelay=0.000000E+000
|RECORD=2|OwnerIndex=332|OwnerPartId=3|FormalType=1|PinConglomerate=56|PinLength=30|Location.X=550|Location.Y=618|Name=76|Designator=C-76|PinPropagationDelay=0.000000E+000
|RECORD=2|OwnerIndex=332|OwnerPartId=3|FormalType=1|PinConglomerate=58|PinLength=30|Location.X=490|Location.Y=608|Name=77|Designator=C-77|PinPropagationDelay=0.000000E+000
|RECORD=2|OwnerIndex=332|OwnerPartId=3|FormalType=1|PinConglomerate=56|PinLength=30|Location.X=550|Location.Y=608|Name=78|Designator=C-78|PinPropagationDelay=0.000000E+000
|RECORD=2|OwnerIndex=332|OwnerPartId=3|FormalType=1|PinConglomerate=58|PinLength=30|Location.X=490|Location.Y=598|Name=79|Designator=C-79|PinPropagationDelay=0.000000E+000
|RECORD=2|OwnerIndex=332|OwnerPartId=3|FormalType=1|PinConglomerate=56|PinLength=30|Location.X=550|Location.Y=598|Name=80|Designator=C-80|PinPropagationDelay=0.000000E+000
|RECORD=2|OwnerIndex=332|OwnerPartId=3|FormalType=1|PinConglomerate=58|PinLength=30|Location.X=490|Location.Y=588|Name=81|Designator=C-81|PinPropagationDelay=0.000000E+000
|RECORD=2|OwnerIndex=332|OwnerPartId=3|FormalType=1|PinConglomerate=56|PinLength=30|Location.X=550|Location.Y=588|Name=82|Designator=C-82|PinPropagationDelay=0.000000E+000
|RECORD=2|OwnerIndex=332|OwnerPartId=3|FormalType=1|PinConglomerate=58|PinLength=30|Location.X=490|Location.Y=578|Name=83|Designator=C-83|PinPropagationDelay=0.000000E+000
|RECORD=2|OwnerIndex=332|OwnerPartId=3|FormalType=1|PinConglomerate=56|PinLength=30|Location.X=550|Location.Y=578|Name=84|Designator=C-84|PinPropagationDelay=0.000000E+000
|RECORD=14|OwnerIndex=332|IsNotAccesible=T|IndexInSheet=170|OwnerPartId=4|Location.X=490|Location.Y=568|Corner.X=550|Corner.Y=998|Color=128|AreaColor=11599871|IsSolid=T
|RECORD=2|OwnerIndex=332|OwnerPartId=4|FormalType=1|PinConglomerate=58|PinLength=30|Location.X=490|Location.Y=988|Name=1|Designator=D-1|PinPropagationDelay=0.000000E+000
|RECORD=2|OwnerIndex=332|OwnerPartId=4|FormalType=1|PinConglomerate=56|PinLength=30|Location.X=550|Location.Y=988|Name=2|Designator=D-2|PinPropagationDelay=0.000000E+000
|RECORD=2|OwnerIndex=332|OwnerPartId=4|FormalType=1|PinConglomerate=58|PinLength=30|Location.X=490|Location.Y=978|Name=3|Designator=D-3|PinPropagationDelay=0.000000E+000
|RECORD=2|OwnerIndex=332|OwnerPartId=4|FormalType=1|PinConglomerate=56|PinLength=30|Location.X=550|Location.Y=978|Name=4|Designator=D-4|PinPropagationDelay=0.000000E+000
|RECORD=2|OwnerIndex=332|OwnerPartId=4|FormalType=1|PinConglomerate=58|PinLength=30|Location.X=490|Location.Y=968|Name=5|Designator=D-5|PinPropagationDelay=0.000000E+000
|RECORD=2|OwnerIndex=332|OwnerPartId=4|FormalType=1|PinConglomerate=56|PinLength=30|Location.X=550|Location.Y=968|Name=6|Designator=D-6|PinPropagationDelay=0.000000E+000
|RECORD=2|OwnerIndex=332|OwnerPartId=4|FormalType=1|PinConglomerate=58|PinLength=30|Location.X=490|Location.Y=958|Name=7|Designator=D-7|PinPropagationDelay=0.000000E+000
|RECORD=2|OwnerIndex=332|OwnerPartId=4|FormalType=1|PinConglomerate=56|PinLength=30|Location.X=550|Location.Y=958|Name=8|Designator=D-8|PinPropagationDelay=0.000000E+000
|RECORD=2|OwnerIndex=332|OwnerPartId=4|FormalType=1|PinConglomerate=58|PinLength=30|Location.X=490|Location.Y=948|Name=9|Designator=D-9|PinPropagationDelay=0.000000E+000
|RECORD=2|OwnerIndex=332|OwnerPartId=4|FormalType=1|PinConglomerate=56|PinLength=30|Location.X=550|Location.Y=948|Name=10|Designator=D-10|PinPropagationDelay=0.000000E+000
|RECORD=2|OwnerIndex=332|OwnerPartId=4|FormalType=1|PinConglomerate=58|PinLength=30|Location.X=490|Location.Y=938|Name=11|Designator=D-11|PinPropagationDelay=0.000000E+000
|RECORD=2|OwnerIndex=332|OwnerPartId=4|FormalType=1|PinConglomerate=56|PinLength=30|Location.X=550|Location.Y=938|Name=12|Designator=D-12|PinPropagationDelay=0.000000E+000
|RECORD=2|OwnerIndex=332|OwnerPartId=4|FormalType=1|PinConglomerate=58|PinLength=30|Location.X=490|Location.Y=928|Name=13|Designator=D-13|PinPropagationDelay=0.000000E+000
|RECORD=2|OwnerIndex=332|OwnerPartId=4|FormalType=1|PinConglomerate=56|PinLength=30|Location.X=550|Location.Y=928|Name=14|Designator=D-14|PinPropagationDelay=0.000000E+000
|RECORD=2|OwnerIndex=332|OwnerPartId=4|FormalType=1|PinConglomerate=58|PinLength=30|Location.X=490|Location.Y=918|Name=15|Designator=D-15|PinPropagationDelay=0.000000E+000
|RECORD=2|OwnerIndex=332|OwnerPartId=4|FormalType=1|PinConglomerate=56|PinLength=30|Location.X=550|Location.Y=918|Name=16|Designator=D-16|PinPropagationDelay=0.000000E+000
|RECORD=2|OwnerIndex=332|OwnerPartId=4|FormalType=1|PinConglomerate=58|PinLength=30|Location.X=490|Location.Y=908|Name=17|Designator=D-17|PinPropagationDelay=0.000000E+000
|RECORD=2|OwnerIndex=332|OwnerPartId=4|FormalType=1|PinConglomerate=56|PinLength=30|Location.X=550|Location.Y=908|Name=18|Designator=D-18|PinPropagationDelay=0.000000E+000
|RECORD=2|OwnerIndex=332|OwnerPartId=4|FormalType=1|PinConglomerate=58|PinLength=30|Location.X=490|Location.Y=898|Name=19|Designator=D-19|PinPropagationDelay=0.000000E+000
|RECORD=2|OwnerIndex=332|OwnerPartId=4|FormalType=1|PinConglomerate=56|PinLength=30|Location.X=550|Location.Y=898|Name=20|Designator=D-20|PinPropagationDelay=0.000000E+000
|RECORD=2|OwnerIndex=332|OwnerPartId=4|FormalType=1|PinConglomerate=58|PinLength=30|Location.X=490|Location.Y=888|Name=21|Designator=D-21|PinPropagationDelay=0.000000E+000
|RECORD=2|OwnerIndex=332|OwnerPartId=4|FormalType=1|PinConglomerate=56|PinLength=30|Location.X=550|Location.Y=888|Name=22|Designator=D-22|PinPropagationDelay=0.000000E+000
|RECORD=2|OwnerIndex=332|OwnerPartId=4|FormalType=1|PinConglomerate=58|PinLength=30|Location.X=490|Location.Y=878|Name=23|Designator=D-23|PinPropagationDelay=0.000000E+000
|RECORD=2|OwnerIndex=332|OwnerPartId=4|FormalType=1|PinConglomerate=56|PinLength=30|Location.X=550|Location.Y=878|Name=24|Designator=D-24|PinPropagationDelay=0.000000E+000
|RECORD=2|OwnerIndex=332|OwnerPartId=4|FormalType=1|PinConglomerate=58|PinLength=30|Location.X=490|Location.Y=868|Name=25|Designator=D-25|PinPropagationDelay=0.000000E+000
|RECORD=2|OwnerIndex=332|OwnerPartId=4|FormalType=1|PinConglomerate=56|PinLength=30|Location.X=550|Location.Y=868|Name=26|Designator=D-26|PinPropagationDelay=0.000000E+000
|RECORD=2|OwnerIndex=332|OwnerPartId=4|FormalType=1|PinConglomerate=58|PinLength=30|Location.X=490|Location.Y=858|Name=27|Designator=D-27|PinPropagationDelay=0.000000E+000
|RECORD=2|OwnerIndex=332|OwnerPartId=4|FormalType=1|PinConglomerate=56|PinLength=30|Location.X=550|Location.Y=858|Name=28|Designator=D-28|PinPropagationDelay=0.000000E+000
|RECORD=2|OwnerIndex=332|OwnerPartId=4|FormalType=1|PinConglomerate=58|PinLength=30|Location.X=490|Location.Y=848|Name=29|Designator=D-29|PinPropagationDelay=0.000000E+000
|RECORD=2|OwnerIndex=332|OwnerPartId=4|FormalType=1|PinConglomerate=56|PinLength=30|Location.X=550|Location.Y=848|Name=30|Designator=D-30|PinPropagationDelay=0.000000E+000
|RECORD=2|OwnerIndex=332|OwnerPartId=4|FormalType=1|PinConglomerate=58|PinLength=30|Location.X=490|Location.Y=838|Name=31|Designator=D-31|PinPropagationDelay=0.000000E+000
|RECORD=2|OwnerIndex=332|OwnerPartId=4|FormalType=1|PinConglomerate=56|PinLength=30|Location.X=550|Location.Y=838|Name=32|Designator=D-32|PinPropagationDelay=0.000000E+000
|RECORD=2|OwnerIndex=332|OwnerPartId=4|FormalType=1|PinConglomerate=58|PinLength=30|Location.X=490|Location.Y=828|Name=33|Designator=D-33|PinPropagationDelay=0.000000E+000
|RECORD=2|OwnerIndex=332|OwnerPartId=4|FormalType=1|PinConglomerate=56|PinLength=30|Location.X=550|Location.Y=828|Name=34|Designator=D-34|PinPropagationDelay=0.000000E+000
|RECORD=2|OwnerIndex=332|OwnerPartId=4|FormalType=1|PinConglomerate=58|PinLength=30|Location.X=490|Location.Y=818|Name=35|Designator=D-35|PinPropagationDelay=0.000000E+000
|RECORD=2|OwnerIndex=332|OwnerPartId=4|FormalType=1|PinConglomerate=56|PinLength=30|Location.X=550|Location.Y=818|Name=36|Designator=D-36|PinPropagationDelay=0.000000E+000
|RECORD=2|OwnerIndex=332|OwnerPartId=4|FormalType=1|PinConglomerate=58|PinLength=30|Location.X=490|Location.Y=808|Name=37|Designator=D-37|PinPropagationDelay=0.000000E+000
|RECORD=2|OwnerIndex=332|OwnerPartId=4|FormalType=1|PinConglomerate=56|PinLength=30|Location.X=550|Location.Y=808|Name=38|Designator=D-38|PinPropagationDelay=0.000000E+000
|RECORD=2|OwnerIndex=332|OwnerPartId=4|FormalType=1|PinConglomerate=58|PinLength=30|Location.X=490|Location.Y=798|Name=39|Designator=D-39|PinPropagationDelay=0.000000E+000
|RECORD=2|OwnerIndex=332|OwnerPartId=4|FormalType=1|PinConglomerate=56|PinLength=30|Location.X=550|Location.Y=798|Name=40|Designator=D-40|PinPropagationDelay=0.000000E+000
|RECORD=2|OwnerIndex=332|OwnerPartId=4|FormalType=1|PinConglomerate=58|PinLength=30|Location.X=490|Location.Y=788|Name=41|Designator=D-41|PinPropagationDelay=0.000000E+000
|RECORD=2|OwnerIndex=332|OwnerPartId=4|FormalType=1|PinConglomerate=56|PinLength=30|Location.X=550|Location.Y=788|Name=42|Designator=D-42|PinPropagationDelay=0.000000E+000
|RECORD=2|OwnerIndex=332|OwnerPartId=4|FormalType=1|PinConglomerate=58|PinLength=30|Location.X=490|Location.Y=778|Name=43|Designator=D-43|PinPropagationDelay=0.000000E+000
|RECORD=2|OwnerIndex=332|OwnerPartId=4|FormalType=1|PinConglomerate=56|PinLength=30|Location.X=550|Location.Y=778|Name=44|Designator=D-44|PinPropagationDelay=0.000000E+000
|RECORD=2|OwnerIndex=332|OwnerPartId=4|FormalType=1|PinConglomerate=58|PinLength=30|Location.X=490|Location.Y=768|Name=45|Designator=D-45|PinPropagationDelay=0.000000E+000
|RECORD=2|OwnerIndex=332|OwnerPartId=4|FormalType=1|PinConglomerate=56|PinLength=30|Location.X=550|Location.Y=768|Name=46|Designator=D-46|PinPropagationDelay=0.000000E+000
|RECORD=2|OwnerIndex=332|OwnerPartId=4|FormalType=1|PinConglomerate=58|PinLength=30|Location.X=490|Location.Y=758|Name=47|Designator=D-47|PinPropagationDelay=0.000000E+000
|RECORD=2|OwnerIndex=332|OwnerPartId=4|FormalType=1|PinConglomerate=56|PinLength=30|Location.X=550|Location.Y=758|Name=48|Designator=D-48|PinPropagationDelay=0.000000E+000
|RECORD=2|OwnerIndex=332|OwnerPartId=4|FormalType=1|PinConglomerate=58|PinLength=30|Location.X=490|Location.Y=748|Name=49|Designator=D-49|PinPropagationDelay=0.000000E+000
|RECORD=2|OwnerIndex=332|OwnerPartId=4|FormalType=1|PinConglomerate=56|PinLength=30|Location.X=550|Location.Y=748|Name=50|Designator=D-50|PinPropagationDelay=0.000000E+000
|RECORD=2|OwnerIndex=332|OwnerPartId=4|FormalType=1|PinConglomerate=58|PinLength=30|Location.X=490|Location.Y=738|Name=51|Designator=D-51|PinPropagationDelay=0.000000E+000
|RECORD=2|OwnerIndex=332|OwnerPartId=4|FormalType=1|PinConglomerate=56|PinLength=30|Location.X=550|Location.Y=738|Name=52|Designator=D-52|PinPropagationDelay=0.000000E+000
|RECORD=2|OwnerIndex=332|OwnerPartId=4|FormalType=1|PinConglomerate=58|PinLength=30|Location.X=490|Location.Y=728|Name=53|Designator=D-53|PinPropagationDelay=0.000000E+000
|RECORD=2|OwnerIndex=332|OwnerPartId=4|FormalType=1|PinConglomerate=56|PinLength=30|Location.X=550|Location.Y=728|Name=54|Designator=D-54|PinPropagationDelay=0.000000E+000
|RECORD=2|OwnerIndex=332|OwnerPartId=4|FormalType=1|PinConglomerate=58|PinLength=30|Location.X=490|Location.Y=718|Name=55|Designator=D-55|PinPropagationDelay=0.000000E+000
|RECORD=2|OwnerIndex=332|OwnerPartId=4|FormalType=1|PinConglomerate=56|PinLength=30|Location.X=550|Location.Y=718|Name=56|Designator=D-56|PinPropagationDelay=0.000000E+000
|RECORD=2|OwnerIndex=332|OwnerPartId=4|FormalType=1|PinConglomerate=58|PinLength=30|Location.X=490|Location.Y=708|Name=57|Designator=D-57|PinPropagationDelay=0.000000E+000
|RECORD=2|OwnerIndex=332|OwnerPartId=4|FormalType=1|PinConglomerate=56|PinLength=30|Location.X=550|Location.Y=708|Name=58|Designator=D-58|PinPropagationDelay=0.000000E+000
|RECORD=2|OwnerIndex=332|OwnerPartId=4|FormalType=1|PinConglomerate=58|PinLength=30|Location.X=490|Location.Y=698|Name=59|Designator=D-59|PinPropagationDelay=0.000000E+000
|RECORD=2|OwnerIndex=332|OwnerPartId=4|FormalType=1|PinConglomerate=56|PinLength=30|Location.X=550|Location.Y=698|Name=60|Designator=D-60|PinPropagationDelay=0.000000E+000
|RECORD=2|OwnerIndex=332|OwnerPartId=4|FormalType=1|PinConglomerate=58|PinLength=30|Location.X=490|Location.Y=688|Name=61|Designator=D-61|PinPropagationDelay=0.000000E+000
|RECORD=2|OwnerIndex=332|OwnerPartId=4|FormalType=1|PinConglomerate=56|PinLength=30|Location.X=550|Location.Y=688|Name=62|Designator=D-62|PinPropagationDelay=0.000000E+000
|RECORD=2|OwnerIndex=332|OwnerPartId=4|FormalType=1|PinConglomerate=58|PinLength=30|Location.X=490|Location.Y=678|Name=63|Designator=D-63|PinPropagationDelay=0.000000E+000
|RECORD=2|OwnerIndex=332|OwnerPartId=4|FormalType=1|PinConglomerate=56|PinLength=30|Location.X=550|Location.Y=678|Name=64|Designator=D-64|PinPropagationDelay=0.000000E+000
|RECORD=2|OwnerIndex=332|OwnerPartId=4|FormalType=1|PinConglomerate=58|PinLength=30|Location.X=490|Location.Y=668|Name=65|Designator=D-65|PinPropagationDelay=0.000000E+000
|RECORD=2|OwnerIndex=332|OwnerPartId=4|FormalType=1|PinConglomerate=56|PinLength=30|Location.X=550|Location.Y=668|Name=66|Designator=D-66|PinPropagationDelay=0.000000E+000
|RECORD=2|OwnerIndex=332|OwnerPartId=4|FormalType=1|PinConglomerate=58|PinLength=30|Location.X=490|Location.Y=658|Name=67|Designator=D-67|PinPropagationDelay=0.000000E+000
|RECORD=2|OwnerIndex=332|OwnerPartId=4|FormalType=1|PinConglomerate=56|PinLength=30|Location.X=550|Location.Y=658|Name=68|Designator=D-68|PinPropagationDelay=0.000000E+000
|RECORD=2|OwnerIndex=332|OwnerPartId=4|FormalType=1|PinConglomerate=58|PinLength=30|Location.X=490|Location.Y=648|Name=69|Designator=D-69|PinPropagationDelay=0.000000E+000
|RECORD=2|OwnerIndex=332|OwnerPartId=4|FormalType=1|PinConglomerate=56|PinLength=30|Location.X=550|Location.Y=648|Name=70|Designator=D-70|PinPropagationDelay=0.000000E+000
|RECORD=2|OwnerIndex=332|OwnerPartId=4|FormalType=1|PinConglomerate=58|PinLength=30|Location.X=490|Location.Y=638|Name=71|Designator=D-71|PinPropagationDelay=0.000000E+000
|RECORD=2|OwnerIndex=332|OwnerPartId=4|FormalType=1|PinConglomerate=56|PinLength=30|Location.X=550|Location.Y=638|Name=72|Designator=D-72|PinPropagationDelay=0.000000E+000
|RECORD=2|OwnerIndex=332|OwnerPartId=4|FormalType=1|PinConglomerate=58|PinLength=30|Location.X=490|Location.Y=628|Name=73|Designator=D-73|PinPropagationDelay=0.000000E+000
|RECORD=2|OwnerIndex=332|OwnerPartId=4|FormalType=1|PinConglomerate=56|PinLength=30|Location.X=550|Location.Y=628|Name=74|Designator=D-74|PinPropagationDelay=0.000000E+000
|RECORD=2|OwnerIndex=332|OwnerPartId=4|FormalType=1|PinConglomerate=58|PinLength=30|Location.X=490|Location.Y=618|Name=75|Designator=D-75|PinPropagationDelay=0.000000E+000
|RECORD=2|OwnerIndex=332|OwnerPartId=4|FormalType=1|PinConglomerate=56|PinLength=30|Location.X=550|Location.Y=618|Name=76|Designator=D-76|PinPropagationDelay=0.000000E+000
|RECORD=2|OwnerIndex=332|OwnerPartId=4|FormalType=1|PinConglomerate=58|PinLength=30|Location.X=490|Location.Y=608|Name=77|Designator=D-77|PinPropagationDelay=0.000000E+000
|RECORD=2|OwnerIndex=332|OwnerPartId=4|FormalType=1|PinConglomerate=56|PinLength=30|Location.X=550|Location.Y=608|Name=78|Designator=D-78|PinPropagationDelay=0.000000E+000
|RECORD=2|OwnerIndex=332|OwnerPartId=4|FormalType=1|PinConglomerate=58|PinLength=30|Location.X=490|Location.Y=598|Name=79|Designator=D-79|PinPropagationDelay=0.000000E+000
|RECORD=2|OwnerIndex=332|OwnerPartId=4|FormalType=1|PinConglomerate=56|PinLength=30|Location.X=550|Location.Y=598|Name=80|Designator=D-80|PinPropagationDelay=0.000000E+000
|RECORD=2|OwnerIndex=332|OwnerPartId=4|FormalType=1|PinConglomerate=58|PinLength=30|Location.X=490|Location.Y=588|Name=81|Designator=D-81|PinPropagationDelay=0.000000E+000
|RECORD=2|OwnerIndex=332|OwnerPartId=4|FormalType=1|PinConglomerate=56|PinLength=30|Location.X=550|Location.Y=588|Name=82|Designator=D-82|PinPropagationDelay=0.000000E+000
|RECORD=2|OwnerIndex=332|OwnerPartId=4|FormalType=1|PinConglomerate=58|PinLength=30|Location.X=490|Location.Y=578|Name=83|Designator=D-83|PinPropagationDelay=0.000000E+000
|RECORD=2|OwnerIndex=332|OwnerPartId=4|FormalType=1|PinConglomerate=56|PinLength=30|Location.X=550|Location.Y=578|Name=84|Designator=D-84|PinPropagationDelay=0.000000E+000
|RECORD=14|OwnerIndex=332|IsNotAccesible=T|IndexInSheet=255|OwnerPartId=1|Location.X=490|Location.Y=568|Corner.X=550|Corner.Y=998|Color=128|AreaColor=11599871|IsSolid=T
|RECORD=2|OwnerIndex=332|OwnerPartId=1|FormalType=1|PinConglomerate=58|PinLength=30|Location.X=490|Location.Y=988|Name=1|Designator=A-1|PinPropagationDelay=0.000000E+000
|RECORD=2|OwnerIndex=332|OwnerPartId=1|FormalType=1|PinConglomerate=56|PinLength=30|Location.X=550|Location.Y=988|Name=2|Designator=A-2|PinPropagationDelay=0.000000E+000
|RECORD=2|OwnerIndex=332|OwnerPartId=1|FormalType=1|PinConglomerate=58|PinLength=30|Location.X=490|Location.Y=978|Name=3|Designator=A-3|PinPropagationDelay=0.000000E+000
|RECORD=2|OwnerIndex=332|OwnerPartId=1|FormalType=1|PinConglomerate=56|PinLength=30|Location.X=550|Location.Y=978|Name=4|Designator=A-4|PinPropagationDelay=0.000000E+000
|RECORD=2|OwnerIndex=332|OwnerPartId=1|FormalType=1|PinConglomerate=58|PinLength=30|Location.X=490|Location.Y=968|Name=5|Designator=A-5|PinPropagationDelay=0.000000E+000
|RECORD=2|OwnerIndex=332|OwnerPartId=1|FormalType=1|PinConglomerate=56|PinLength=30|Location.X=550|Location.Y=968|Name=6|Designator=A-6|PinPropagationDelay=0.000000E+000
|RECORD=2|OwnerIndex=332|OwnerPartId=1|FormalType=1|PinConglomerate=58|PinLength=30|Location.X=490|Location.Y=958|Name=7|Designator=A-7|PinPropagationDelay=0.000000E+000
|RECORD=2|OwnerIndex=332|OwnerPartId=1|FormalType=1|PinConglomerate=56|PinLength=30|Location.X=550|Location.Y=958|Name=8|Designator=A-8|PinPropagationDelay=0.000000E+000
|RECORD=2|OwnerIndex=332|OwnerPartId=1|FormalType=1|PinConglomerate=58|PinLength=30|Location.X=490|Location.Y=948|Name=9|Designator=A-9|PinPropagationDelay=0.000000E+000
|RECORD=2|OwnerIndex=332|OwnerPartId=1|FormalType=1|PinConglomerate=56|PinLength=30|Location.X=550|Location.Y=948|Name=10|Designator=A-10|PinPropagationDelay=0.000000E+000
|RECORD=2|OwnerIndex=332|OwnerPartId=1|FormalType=1|PinConglomerate=58|PinLength=30|Location.X=490|Location.Y=938|Name=11|Designator=A-11|PinPropagationDelay=0.000000E+000
|RECORD=2|OwnerIndex=332|OwnerPartId=1|FormalType=1|PinConglomerate=56|PinLength=30|Location.X=550|Location.Y=938|Name=12|Designator=A-12|PinPropagationDelay=0.000000E+000
|RECORD=2|OwnerIndex=332|OwnerPartId=1|FormalType=1|PinConglomerate=58|PinLength=30|Location.X=490|Location.Y=928|Name=13|Designator=A-13|PinPropagationDelay=0.000000E+000
|RECORD=2|OwnerIndex=332|OwnerPartId=1|FormalType=1|PinConglomerate=56|PinLength=30|Location.X=550|Location.Y=928|Name=14|Designator=A-14|PinPropagationDelay=0.000000E+000
|RECORD=2|OwnerIndex=332|OwnerPartId=1|FormalType=1|PinConglomerate=58|PinLength=30|Location.X=490|Location.Y=918|Name=15|Designator=A-15|PinPropagationDelay=0.000000E+000
|RECORD=2|OwnerIndex=332|OwnerPartId=1|FormalType=1|PinConglomerate=56|PinLength=30|Location.X=550|Location.Y=918|Name=16|Designator=A-16|PinPropagationDelay=0.000000E+000
|RECORD=2|OwnerIndex=332|OwnerPartId=1|FormalType=1|PinConglomerate=58|PinLength=30|Location.X=490|Location.Y=908|Name=17|Designator=A-17|PinPropagationDelay=0.000000E+000
|RECORD=2|OwnerIndex=332|OwnerPartId=1|FormalType=1|PinConglomerate=56|PinLength=30|Location.X=550|Location.Y=908|Name=18|Designator=A-18|PinPropagationDelay=0.000000E+000
|RECORD=2|OwnerIndex=332|OwnerPartId=1|FormalType=1|PinConglomerate=58|PinLength=30|Location.X=490|Location.Y=898|Name=19|Designator=A-19|PinPropagationDelay=0.000000E+000
|RECORD=2|OwnerIndex=332|OwnerPartId=1|FormalType=1|PinConglomerate=56|PinLength=30|Location.X=550|Location.Y=898|Name=20|Designator=A-20|PinPropagationDelay=0.000000E+000
|RECORD=2|OwnerIndex=332|OwnerPartId=1|FormalType=1|PinConglomerate=58|PinLength=30|Location.X=490|Location.Y=888|Name=21|Designator=A-21|PinPropagationDelay=0.000000E+000
|RECORD=2|OwnerIndex=332|OwnerPartId=1|FormalType=1|PinConglomerate=56|PinLength=30|Location.X=550|Location.Y=888|Name=22|Designator=A-22|PinPropagationDelay=0.000000E+000
|RECORD=2|OwnerIndex=332|OwnerPartId=1|FormalType=1|PinConglomerate=58|PinLength=30|Location.X=490|Location.Y=878|Name=23|Designator=A-23|PinPropagationDelay=0.000000E+000
|RECORD=2|OwnerIndex=332|OwnerPartId=1|FormalType=1|PinConglomerate=56|PinLength=30|Location.X=550|Location.Y=878|Name=24|Designator=A-24|PinPropagationDelay=0.000000E+000
|RECORD=2|OwnerIndex=332|OwnerPartId=1|FormalType=1|PinConglomerate=58|PinLength=30|Location.X=490|Location.Y=868|Name=25|Designator=A-25|PinPropagationDelay=0.000000E+000
|RECORD=2|OwnerIndex=332|OwnerPartId=1|FormalType=1|PinConglomerate=56|PinLength=30|Location.X=550|Location.Y=868|Name=26|Designator=A-26|PinPropagationDelay=0.000000E+000
|RECORD=2|OwnerIndex=332|OwnerPartId=1|FormalType=1|PinConglomerate=58|PinLength=30|Location.X=490|Location.Y=858|Name=27|Designator=A-27|PinPropagationDelay=0.000000E+000
|RECORD=2|OwnerIndex=332|OwnerPartId=1|FormalType=1|PinConglomerate=56|PinLength=30|Location.X=550|Location.Y=858|Name=28|Designator=A-28|PinPropagationDelay=0.000000E+000
|RECORD=2|OwnerIndex=332|OwnerPartId=1|FormalType=1|PinConglomerate=58|PinLength=30|Location.X=490|Location.Y=848|Name=29|Designator=A-29|PinPropagationDelay=0.000000E+000
|RECORD=2|OwnerIndex=332|OwnerPartId=1|FormalType=1|PinConglomerate=56|PinLength=30|Location.X=550|Location.Y=848|Name=30|Designator=A-30|PinPropagationDelay=0.000000E+000
|RECORD=2|OwnerIndex=332|OwnerPartId=1|FormalType=1|PinConglomerate=58|PinLength=30|Location.X=490|Location.Y=838|Name=31|Designator=A-31|PinPropagationDelay=0.000000E+000
|RECORD=2|OwnerIndex=332|OwnerPartId=1|FormalType=1|PinConglomerate=56|PinLength=30|Location.X=550|Location.Y=838|Name=32|Designator=A-32|PinPropagationDelay=0.000000E+000
|RECORD=2|OwnerIndex=332|OwnerPartId=1|FormalType=1|PinConglomerate=58|PinLength=30|Location.X=490|Location.Y=828|Name=33|Designator=A-33|PinPropagationDelay=0.000000E+000
|RECORD=2|OwnerIndex=332|OwnerPartId=1|FormalType=1|PinConglomerate=56|PinLength=30|Location.X=550|Location.Y=828|Name=34|Designator=A-34|PinPropagationDelay=0.000000E+000
|RECORD=2|OwnerIndex=332|OwnerPartId=1|FormalType=1|PinConglomerate=58|PinLength=30|Location.X=490|Location.Y=818|Name=35|Designator=A-35|PinPropagationDelay=0.000000E+000
|RECORD=2|OwnerIndex=332|OwnerPartId=1|FormalType=1|PinConglomerate=56|PinLength=30|Location.X=550|Location.Y=818|Name=36|Designator=A-36|PinPropagationDelay=0.000000E+000
|RECORD=2|OwnerIndex=332|OwnerPartId=1|FormalType=1|PinConglomerate=58|PinLength=30|Location.X=490|Location.Y=808|Name=37|Designator=A-37|PinPropagationDelay=0.000000E+000
|RECORD=2|OwnerIndex=332|OwnerPartId=1|FormalType=1|PinConglomerate=56|PinLength=30|Location.X=550|Location.Y=808|Name=38|Designator=A-38|PinPropagationDelay=0.000000E+000
|RECORD=2|OwnerIndex=332|OwnerPartId=1|FormalType=1|PinConglomerate=58|PinLength=30|Location.X=490|Location.Y=798|Name=39|Designator=A-39|PinPropagationDelay=0.000000E+000
|RECORD=2|OwnerIndex=332|OwnerPartId=1|FormalType=1|PinConglomerate=56|PinLength=30|Location.X=550|Location.Y=798|Name=40|Designator=A-40|PinPropagationDelay=0.000000E+000
|RECORD=2|OwnerIndex=332|OwnerPartId=1|FormalType=1|PinConglomerate=58|PinLength=30|Location.X=490|Location.Y=788|Name=41|Designator=A-41|PinPropagationDelay=0.000000E+000
|RECORD=2|OwnerIndex=332|OwnerPartId=1|FormalType=1|PinConglomerate=56|PinLength=30|Location.X=550|Location.Y=788|Name=42|Designator=A-42|PinPropagationDelay=0.000000E+000
|RECORD=2|OwnerIndex=332|OwnerPartId=1|FormalType=1|PinConglomerate=58|PinLength=30|Location.X=490|Location.Y=778|Name=43|Designator=A-43|PinPropagationDelay=0.000000E+000
|RECORD=2|OwnerIndex=332|OwnerPartId=1|FormalType=1|PinConglomerate=56|PinLength=30|Location.X=550|Location.Y=778|Name=44|Designator=A-44|PinPropagationDelay=0.000000E+000
|RECORD=2|OwnerIndex=332|OwnerPartId=1|FormalType=1|PinConglomerate=58|PinLength=30|Location.X=490|Location.Y=768|Name=45|Designator=A-45|PinPropagationDelay=0.000000E+000
|RECORD=2|OwnerIndex=332|OwnerPartId=1|FormalType=1|PinConglomerate=56|PinLength=30|Location.X=550|Location.Y=768|Name=46|Designator=A-46|PinPropagationDelay=0.000000E+000
|RECORD=2|OwnerIndex=332|OwnerPartId=1|FormalType=1|PinConglomerate=58|PinLength=30|Location.X=490|Location.Y=758|Name=47|Designator=A-47|PinPropagationDelay=0.000000E+000
|RECORD=2|OwnerIndex=332|OwnerPartId=1|FormalType=1|PinConglomerate=56|PinLength=30|Location.X=550|Location.Y=758|Name=48|Designator=A-48|PinPropagationDelay=0.000000E+000
|RECORD=2|OwnerIndex=332|OwnerPartId=1|FormalType=1|PinConglomerate=58|PinLength=30|Location.X=490|Location.Y=748|Name=49|Designator=A-49|PinPropagationDelay=0.000000E+000
|RECORD=2|OwnerIndex=332|OwnerPartId=1|FormalType=1|PinConglomerate=56|PinLength=30|Location.X=550|Location.Y=748|Name=50|Designator=A-50|PinPropagationDelay=0.000000E+000
|RECORD=2|OwnerIndex=332|OwnerPartId=1|FormalType=1|PinConglomerate=58|PinLength=30|Location.X=490|Location.Y=738|Name=51|Designator=A-51|PinPropagationDelay=0.000000E+000
|RECORD=2|OwnerIndex=332|OwnerPartId=1|FormalType=1|PinConglomerate=56|PinLength=30|Location.X=550|Location.Y=738|Name=52|Designator=A-52|PinPropagationDelay=0.000000E+000
|RECORD=2|OwnerIndex=332|OwnerPartId=1|FormalType=1|PinConglomerate=58|PinLength=30|Location.X=490|Location.Y=728|Name=53|Designator=A-53|PinPropagationDelay=0.000000E+000
|RECORD=2|OwnerIndex=332|OwnerPartId=1|FormalType=1|PinConglomerate=56|PinLength=30|Location.X=550|Location.Y=728|Name=54|Designator=A-54|PinPropagationDelay=0.000000E+000
|RECORD=2|OwnerIndex=332|OwnerPartId=1|FormalType=1|PinConglomerate=58|PinLength=30|Location.X=490|Location.Y=718|Name=55|Designator=A-55|PinPropagationDelay=0.000000E+000
|RECORD=2|OwnerIndex=332|OwnerPartId=1|FormalType=1|PinConglomerate=56|PinLength=30|Location.X=550|Location.Y=718|Name=56|Designator=A-56|PinPropagationDelay=0.000000E+000
|RECORD=2|OwnerIndex=332|OwnerPartId=1|FormalType=1|PinConglomerate=58|PinLength=30|Location.X=490|Location.Y=708|Name=57|Designator=A-57|PinPropagationDelay=0.000000E+000
|RECORD=2|OwnerIndex=332|OwnerPartId=1|FormalType=1|PinConglomerate=56|PinLength=30|Location.X=550|Location.Y=708|Name=58|Designator=A-58|PinPropagationDelay=0.000000E+000
|RECORD=2|OwnerIndex=332|OwnerPartId=1|FormalType=1|PinConglomerate=58|PinLength=30|Location.X=490|Location.Y=698|Name=59|Designator=A-59|PinPropagationDelay=0.000000E+000
|RECORD=2|OwnerIndex=332|OwnerPartId=1|FormalType=1|PinConglomerate=56|PinLength=30|Location.X=550|Location.Y=698|Name=60|Designator=A-60|PinPropagationDelay=0.000000E+000
|RECORD=2|OwnerIndex=332|OwnerPartId=1|FormalType=1|PinConglomerate=58|PinLength=30|Location.X=490|Location.Y=688|Name=61|Designator=A-61|PinPropagationDelay=0.000000E+000
|RECORD=2|OwnerIndex=332|OwnerPartId=1|FormalType=1|PinConglomerate=56|PinLength=30|Location.X=550|Location.Y=688|Name=62|Designator=A-62|PinPropagationDelay=0.000000E+000
|RECORD=2|OwnerIndex=332|OwnerPartId=1|FormalType=1|PinConglomerate=58|PinLength=30|Location.X=490|Location.Y=678|Name=63|Designator=A-63|PinPropagationDelay=0.000000E+000
|RECORD=2|OwnerIndex=332|OwnerPartId=1|FormalType=1|PinConglomerate=56|PinLength=30|Location.X=550|Location.Y=678|Name=64|Designator=A-64|PinPropagationDelay=0.000000E+000
|RECORD=2|OwnerIndex=332|OwnerPartId=1|FormalType=1|PinConglomerate=58|PinLength=30|Location.X=490|Location.Y=668|Name=65|Designator=A-65|PinPropagationDelay=0.000000E+000
|RECORD=2|OwnerIndex=332|OwnerPartId=1|FormalType=1|PinConglomerate=56|PinLength=30|Location.X=550|Location.Y=668|Name=66|Designator=A-66|PinPropagationDelay=0.000000E+000
|RECORD=2|OwnerIndex=332|OwnerPartId=1|FormalType=1|PinConglomerate=58|PinLength=30|Location.X=490|Location.Y=658|Name=67|Designator=A-67|PinPropagationDelay=0.000000E+000
|RECORD=2|OwnerIndex=332|OwnerPartId=1|FormalType=1|PinConglomerate=56|PinLength=30|Location.X=550|Location.Y=658|Name=68|Designator=A-68|PinPropagationDelay=0.000000E+000
|RECORD=2|OwnerIndex=332|OwnerPartId=1|FormalType=1|PinConglomerate=58|PinLength=30|Location.X=490|Location.Y=648|Name=69|Designator=A-69|PinPropagationDelay=0.000000E+000
|RECORD=2|OwnerIndex=332|OwnerPartId=1|FormalType=1|PinConglomerate=56|PinLength=30|Location.X=550|Location.Y=648|Name=70|Designator=A-70|PinPropagationDelay=0.000000E+000
|RECORD=2|OwnerIndex=332|OwnerPartId=1|FormalType=1|PinConglomerate=58|PinLength=30|Location.X=490|Location.Y=638|Name=71|Designator=A-71|PinPropagationDelay=0.000000E+000
|RECORD=2|OwnerIndex=332|OwnerPartId=1|FormalType=1|PinConglomerate=56|PinLength=30|Location.X=550|Location.Y=638|Name=72|Designator=A-72|PinPropagationDelay=0.000000E+000
|RECORD=2|OwnerIndex=332|OwnerPartId=1|FormalType=1|PinConglomerate=58|PinLength=30|Location.X=490|Location.Y=628|Name=73|Designator=A-73|PinPropagationDelay=0.000000E+000
|RECORD=2|OwnerIndex=332|OwnerPartId=1|FormalType=1|PinConglomerate=56|PinLength=30|Location.X=550|Location.Y=628|Name=74|Designator=A-74|PinPropagationDelay=0.000000E+000
|RECORD=2|OwnerIndex=332|OwnerPartId=1|FormalType=1|PinConglomerate=58|PinLength=30|Location.X=490|Location.Y=618|Name=75|Designator=A-75|PinPropagationDelay=0.000000E+000
|RECORD=2|OwnerIndex=332|OwnerPartId=1|FormalType=1|PinConglomerate=56|PinLength=30|Location.X=550|Location.Y=618|Name=76|Designator=A-76|PinPropagationDelay=0.000000E+000
|RECORD=2|OwnerIndex=332|OwnerPartId=1|FormalType=1|PinConglomerate=58|PinLength=30|Location.X=490|Location.Y=608|Name=77|Designator=A-77|PinPropagationDelay=0.000000E+000
|RECORD=2|OwnerIndex=332|OwnerPartId=1|FormalType=1|PinConglomerate=56|PinLength=30|Location.X=550|Location.Y=608|Name=78|Designator=A-78|PinPropagationDelay=0.000000E+000
|RECORD=2|OwnerIndex=332|OwnerPartId=1|FormalType=1|PinConglomerate=58|PinLength=30|Location.X=490|Location.Y=598|Name=79|Designator=A-79|PinPropagationDelay=0.000000E+000
|RECORD=2|OwnerIndex=332|OwnerPartId=1|FormalType=1|PinConglomerate=56|PinLength=30|Location.X=550|Location.Y=598|Name=80|Designator=A-80|PinPropagationDelay=0.000000E+000
|RECORD=2|OwnerIndex=332|OwnerPartId=1|FormalType=1|PinConglomerate=58|PinLength=30|Location.X=490|Location.Y=588|Name=81|Designator=A-81|PinPropagationDelay=0.000000E+000
|RECORD=2|OwnerIndex=332|OwnerPartId=1|FormalType=1|PinConglomerate=56|PinLength=30|Location.X=550|Location.Y=588|Name=82|Designator=A-82|PinPropagationDelay=0.000000E+000
|RECORD=2|OwnerIndex=332|OwnerPartId=1|FormalType=1|PinConglomerate=58|PinLength=30|Location.X=490|Location.Y=578|Name=83|Designator=A-83|PinPropagationDelay=0.000000E+000
|RECORD=2|OwnerIndex=332|OwnerPartId=1|FormalType=1|PinConglomerate=56|PinLength=30|Location.X=550|Location.Y=578|Name=84|Designator=A-84|PinPropagationDelay=0.000000E+000
|RECORD=34|OwnerIndex=332|IndexInSheet=-1|OwnerPartId=-1|Location.X=490|Location.Y=998|Color=8388608|FontID=1|Text=P1|Name=Designator|ReadOnlyState=1
|RECORD=41|OwnerIndex=332|IndexInSheet=-1|OwnerPartId=-1|Location.X=490|Location.Y=558|Color=8388608|FontID=1|Text=FPGA_CONN|Name=Comment
|RECORD=44|OwnerIndex=332
|RECORD=45|OwnerIndex=1011|IndexInSheet=-1|ModelName=FPGA_CONN|ModelType=PCBLIB|DatafileCount=1|ModelDatafileEntity0=FPGA_CONN|ModelDatafileKind0=PCBLib|IsCurrent=T
|RECORD=46|OwnerIndex=1012
|RECORD=48|OwnerIndex=1012
|RECORD=1|LibReference=FPGA_CONN|PartCount=5|DisplayModeCount=1|IndexInSheet=304|OwnerPartId=-1|Location.X=1170|Location.Y=988|CurrentPartId=2|LibraryPath=*|SourceLibraryName=FPGA_CONN.SchLib|TargetFileName=*|AreaColor=11599871|Color=128|PartIDLocked=T|NotUseDBTableName=T|DesignItemId=FPGA_CONN|AllPinCount=336
|RECORD=14|OwnerIndex=1015|IsNotAccesible=T|OwnerPartId=2|Location.X=1200|Location.Y=568|Corner.X=1260|Corner.Y=998|Color=128|AreaColor=11599871|IsSolid=T
|RECORD=2|OwnerIndex=1015|OwnerPartId=2|FormalType=1|PinConglomerate=58|PinLength=30|Location.X=1200|Location.Y=988|Name=1|Designator=B-1|PinPropagationDelay=0.000000E+000
|RECORD=2|OwnerIndex=1015|OwnerPartId=2|FormalType=1|PinConglomerate=56|PinLength=30|Location.X=1260|Location.Y=988|Name=2|Designator=B-2|PinPropagationDelay=0.000000E+000
|RECORD=2|OwnerIndex=1015|OwnerPartId=2|FormalType=1|PinConglomerate=58|PinLength=30|Location.X=1200|Location.Y=978|Name=3|Designator=B-3|PinPropagationDelay=0.000000E+000
|RECORD=2|OwnerIndex=1015|OwnerPartId=2|FormalType=1|PinConglomerate=56|PinLength=30|Location.X=1260|Location.Y=978|Name=4|Designator=B-4|PinPropagationDelay=0.000000E+000
|RECORD=2|OwnerIndex=1015|OwnerPartId=2|FormalType=1|PinConglomerate=58|PinLength=30|Location.X=1200|Location.Y=968|Name=5|Designator=B-5|PinPropagationDelay=0.000000E+000
|RECORD=2|OwnerIndex=1015|OwnerPartId=2|FormalType=1|PinConglomerate=56|PinLength=30|Location.X=1260|Location.Y=968|Name=6|Designator=B-6|PinPropagationDelay=0.000000E+000
|RECORD=2|OwnerIndex=1015|OwnerPartId=2|FormalType=1|PinConglomerate=58|PinLength=30|Location.X=1200|Location.Y=958|Name=7|Designator=B-7|PinPropagationDelay=0.000000E+000
|RECORD=2|OwnerIndex=1015|OwnerPartId=2|FormalType=1|PinConglomerate=56|PinLength=30|Location.X=1260|Location.Y=958|Name=8|Designator=B-8|PinPropagationDelay=0.000000E+000
|RECORD=2|OwnerIndex=1015|OwnerPartId=2|FormalType=1|PinConglomerate=58|PinLength=30|Location.X=1200|Location.Y=948|Name=9|Designator=B-9|PinPropagationDelay=0.000000E+000
|RECORD=2|OwnerIndex=1015|OwnerPartId=2|FormalType=1|PinConglomerate=56|PinLength=30|Location.X=1260|Location.Y=948|Name=10|Designator=B-10|PinPropagationDelay=0.000000E+000
|RECORD=2|OwnerIndex=1015|OwnerPartId=2|FormalType=1|PinConglomerate=58|PinLength=30|Location.X=1200|Location.Y=938|Name=11|Designator=B-11|PinPropagationDelay=0.000000E+000
|RECORD=2|OwnerIndex=1015|OwnerPartId=2|FormalType=1|PinConglomerate=56|PinLength=30|Location.X=1260|Location.Y=938|Name=12|Designator=B-12|PinPropagationDelay=0.000000E+000
|RECORD=2|OwnerIndex=1015|OwnerPartId=2|FormalType=1|PinConglomerate=58|PinLength=30|Location.X=1200|Location.Y=928|Name=13|Designator=B-13|PinPropagationDelay=0.000000E+000
|RECORD=2|OwnerIndex=1015|OwnerPartId=2|FormalType=1|PinConglomerate=56|PinLength=30|Location.X=1260|Location.Y=928|Name=14|Designator=B-14|PinPropagationDelay=0.000000E+000
|RECORD=2|OwnerIndex=1015|OwnerPartId=2|FormalType=1|PinConglomerate=58|PinLength=30|Location.X=1200|Location.Y=918|Name=15|Designator=B-15|PinPropagationDelay=0.000000E+000
|RECORD=2|OwnerIndex=1015|OwnerPartId=2|FormalType=1|PinConglomerate=56|PinLength=30|Location.X=1260|Location.Y=918|Name=16|Designator=B-16|PinPropagationDelay=0.000000E+000
|RECORD=2|OwnerIndex=1015|OwnerPartId=2|FormalType=1|PinConglomerate=58|PinLength=30|Location.X=1200|Location.Y=908|Name=17|Designator=B-17|PinPropagationDelay=0.000000E+000
|RECORD=2|OwnerIndex=1015|OwnerPartId=2|FormalType=1|PinConglomerate=56|PinLength=30|Location.X=1260|Location.Y=908|Name=18|Designator=B-18|PinPropagationDelay=0.000000E+000
|RECORD=2|OwnerIndex=1015|OwnerPartId=2|FormalType=1|PinConglomerate=58|PinLength=30|Location.X=1200|Location.Y=898|Name=19|Designator=B-19|PinPropagationDelay=0.000000E+000
|RECORD=2|OwnerIndex=1015|OwnerPartId=2|FormalType=1|PinConglomerate=56|PinLength=30|Location.X=1260|Location.Y=898|Name=20|Designator=B-20|PinPropagationDelay=0.000000E+000
|RECORD=2|OwnerIndex=1015|OwnerPartId=2|FormalType=1|PinConglomerate=58|PinLength=30|Location.X=1200|Location.Y=888|Name=21|Designator=B-21|PinPropagationDelay=0.000000E+000
|RECORD=2|OwnerIndex=1015|OwnerPartId=2|FormalType=1|PinConglomerate=56|PinLength=30|Location.X=1260|Location.Y=888|Name=22|Designator=B-22|PinPropagationDelay=0.000000E+000
|RECORD=2|OwnerIndex=1015|OwnerPartId=2|FormalType=1|PinConglomerate=58|PinLength=30|Location.X=1200|Location.Y=878|Name=23|Designator=B-23|PinPropagationDelay=0.000000E+000
|RECORD=2|OwnerIndex=1015|OwnerPartId=2|FormalType=1|PinConglomerate=56|PinLength=30|Location.X=1260|Location.Y=878|Name=24|Designator=B-24|PinPropagationDelay=0.000000E+000
|RECORD=2|OwnerIndex=1015|OwnerPartId=2|FormalType=1|PinConglomerate=58|PinLength=30|Location.X=1200|Location.Y=868|Name=25|Designator=B-25|PinPropagationDelay=0.000000E+000
|RECORD=2|OwnerIndex=1015|OwnerPartId=2|FormalType=1|PinConglomerate=56|PinLength=30|Location.X=1260|Location.Y=868|Name=26|Designator=B-26|PinPropagationDelay=0.000000E+000
|RECORD=2|OwnerIndex=1015|OwnerPartId=2|FormalType=1|PinConglomerate=58|PinLength=30|Location.X=1200|Location.Y=858|Name=27|Designator=B-27|PinPropagationDelay=0.000000E+000
|RECORD=2|OwnerIndex=1015|OwnerPartId=2|FormalType=1|PinConglomerate=56|PinLength=30|Location.X=1260|Location.Y=858|Name=28|Designator=B-28|PinPropagationDelay=0.000000E+000
|RECORD=2|OwnerIndex=1015|OwnerPartId=2|FormalType=1|PinConglomerate=58|PinLength=30|Location.X=1200|Location.Y=848|Name=29|Designator=B-29|PinPropagationDelay=0.000000E+000
|RECORD=2|OwnerIndex=1015|OwnerPartId=2|FormalType=1|PinConglomerate=56|PinLength=30|Location.X=1260|Location.Y=848|Name=30|Designator=B-30|PinPropagationDelay=0.000000E+000
|RECORD=2|OwnerIndex=1015|OwnerPartId=2|FormalType=1|PinConglomerate=58|PinLength=30|Location.X=1200|Location.Y=838|Name=31|Designator=B-31|PinPropagationDelay=0.000000E+000
|RECORD=2|OwnerIndex=1015|OwnerPartId=2|FormalType=1|PinConglomerate=56|PinLength=30|Location.X=1260|Location.Y=838|Name=32|Designator=B-32|PinPropagationDelay=0.000000E+000
|RECORD=2|OwnerIndex=1015|OwnerPartId=2|FormalType=1|PinConglomerate=58|PinLength=30|Location.X=1200|Location.Y=828|Name=33|Designator=B-33|PinPropagationDelay=0.000000E+000
|RECORD=2|OwnerIndex=1015|OwnerPartId=2|FormalType=1|PinConglomerate=56|PinLength=30|Location.X=1260|Location.Y=828|Name=34|Designator=B-34|PinPropagationDelay=0.000000E+000
|RECORD=2|OwnerIndex=1015|OwnerPartId=2|FormalType=1|PinConglomerate=58|PinLength=30|Location.X=1200|Location.Y=818|Name=35|Designator=B-35|PinPropagationDelay=0.000000E+000
|RECORD=2|OwnerIndex=1015|OwnerPartId=2|FormalType=1|PinConglomerate=56|PinLength=30|Location.X=1260|Location.Y=818|Name=36|Designator=B-36|PinPropagationDelay=0.000000E+000
|RECORD=2|OwnerIndex=1015|OwnerPartId=2|FormalType=1|PinConglomerate=58|PinLength=30|Location.X=1200|Location.Y=808|Name=37|Designator=B-37|PinPropagationDelay=0.000000E+000
|RECORD=2|OwnerIndex=1015|OwnerPartId=2|FormalType=1|PinConglomerate=56|PinLength=30|Location.X=1260|Location.Y=808|Name=38|Designator=B-38|PinPropagationDelay=0.000000E+000
|RECORD=2|OwnerIndex=1015|OwnerPartId=2|FormalType=1|PinConglomerate=58|PinLength=30|Location.X=1200|Location.Y=798|Name=39|Designator=B-39|PinPropagationDelay=0.000000E+000
|RECORD=2|OwnerIndex=1015|OwnerPartId=2|FormalType=1|PinConglomerate=56|PinLength=30|Location.X=1260|Location.Y=798|Name=40|Designator=B-40|PinPropagationDelay=0.000000E+000
|RECORD=2|OwnerIndex=1015|OwnerPartId=2|FormalType=1|PinConglomerate=58|PinLength=30|Location.X=1200|Location.Y=788|Name=41|Designator=B-41|PinPropagationDelay=0.000000E+000
|RECORD=2|OwnerIndex=1015|OwnerPartId=2|FormalType=1|PinConglomerate=56|PinLength=30|Location.X=1260|Location.Y=788|Name=42|Designator=B-42|PinPropagationDelay=0.000000E+000
|RECORD=2|OwnerIndex=1015|OwnerPartId=2|FormalType=1|PinConglomerate=58|PinLength=30|Location.X=1200|Location.Y=778|Name=43|Designator=B-43|PinPropagationDelay=0.000000E+000
|RECORD=2|OwnerIndex=1015|OwnerPartId=2|FormalType=1|PinConglomerate=56|PinLength=30|Location.X=1260|Location.Y=778|Name=44|Designator=B-44|PinPropagationDelay=0.000000E+000
|RECORD=2|OwnerIndex=1015|OwnerPartId=2|FormalType=1|PinConglomerate=58|PinLength=30|Location.X=1200|Location.Y=768|Name=45|Designator=B-45|PinPropagationDelay=0.000000E+000
|RECORD=2|OwnerIndex=1015|OwnerPartId=2|FormalType=1|PinConglomerate=56|PinLength=30|Location.X=1260|Location.Y=768|Name=46|Designator=B-46|PinPropagationDelay=0.000000E+000
|RECORD=2|OwnerIndex=1015|OwnerPartId=2|FormalType=1|PinConglomerate=58|PinLength=30|Location.X=1200|Location.Y=758|Name=47|Designator=B-47|PinPropagationDelay=0.000000E+000
|RECORD=2|OwnerIndex=1015|OwnerPartId=2|FormalType=1|PinConglomerate=56|PinLength=30|Location.X=1260|Location.Y=758|Name=48|Designator=B-48|PinPropagationDelay=0.000000E+000
|RECORD=2|OwnerIndex=1015|OwnerPartId=2|FormalType=1|PinConglomerate=58|PinLength=30|Location.X=1200|Location.Y=748|Name=49|Designator=B-49|PinPropagationDelay=0.000000E+000
|RECORD=2|OwnerIndex=1015|OwnerPartId=2|FormalType=1|PinConglomerate=56|PinLength=30|Location.X=1260|Location.Y=748|Name=50|Designator=B-50|PinPropagationDelay=0.000000E+000
|RECORD=2|OwnerIndex=1015|OwnerPartId=2|FormalType=1|PinConglomerate=58|PinLength=30|Location.X=1200|Location.Y=738|Name=51|Designator=B-51|PinPropagationDelay=0.000000E+000
|RECORD=2|OwnerIndex=1015|OwnerPartId=2|FormalType=1|PinConglomerate=56|PinLength=30|Location.X=1260|Location.Y=738|Name=52|Designator=B-52|PinPropagationDelay=0.000000E+000
|RECORD=2|OwnerIndex=1015|OwnerPartId=2|FormalType=1|PinConglomerate=58|PinLength=30|Location.X=1200|Location.Y=728|Name=53|Designator=B-53|PinPropagationDelay=0.000000E+000
|RECORD=2|OwnerIndex=1015|OwnerPartId=2|FormalType=1|PinConglomerate=56|PinLength=30|Location.X=1260|Location.Y=728|Name=54|Designator=B-54|PinPropagationDelay=0.000000E+000
|RECORD=2|OwnerIndex=1015|OwnerPartId=2|FormalType=1|PinConglomerate=58|PinLength=30|Location.X=1200|Location.Y=718|Name=55|Designator=B-55|PinPropagationDelay=0.000000E+000
|RECORD=2|OwnerIndex=1015|OwnerPartId=2|FormalType=1|PinConglomerate=56|PinLength=30|Location.X=1260|Location.Y=718|Name=56|Designator=B-56|PinPropagationDelay=0.000000E+000
|RECORD=2|OwnerIndex=1015|OwnerPartId=2|FormalType=1|PinConglomerate=58|PinLength=30|Location.X=1200|Location.Y=708|Name=57|Designator=B-57|PinPropagationDelay=0.000000E+000
|RECORD=2|OwnerIndex=1015|OwnerPartId=2|FormalType=1|PinConglomerate=56|PinLength=30|Location.X=1260|Location.Y=708|Name=58|Designator=B-58|PinPropagationDelay=0.000000E+000
|RECORD=2|OwnerIndex=1015|OwnerPartId=2|FormalType=1|PinConglomerate=58|PinLength=30|Location.X=1200|Location.Y=698|Name=59|Designator=B-59|PinPropagationDelay=0.000000E+000
|RECORD=2|OwnerIndex=1015|OwnerPartId=2|FormalType=1|PinConglomerate=56|PinLength=30|Location.X=1260|Location.Y=698|Name=60|Designator=B-60|PinPropagationDelay=0.000000E+000
|RECORD=2|OwnerIndex=1015|OwnerPartId=2|FormalType=1|PinConglomerate=58|PinLength=30|Location.X=1200|Location.Y=688|Name=61|Designator=B-61|PinPropagationDelay=0.000000E+000
|RECORD=2|OwnerIndex=1015|OwnerPartId=2|FormalType=1|PinConglomerate=56|PinLength=30|Location.X=1260|Location.Y=688|Name=62|Designator=B-62|PinPropagationDelay=0.000000E+000
|RECORD=2|OwnerIndex=1015|OwnerPartId=2|FormalType=1|PinConglomerate=58|PinLength=30|Location.X=1200|Location.Y=678|Name=63|Designator=B-63|PinPropagationDelay=0.000000E+000
|RECORD=2|OwnerIndex=1015|OwnerPartId=2|FormalType=1|PinConglomerate=56|PinLength=30|Location.X=1260|Location.Y=678|Name=64|Designator=B-64|PinPropagationDelay=0.000000E+000
|RECORD=2|OwnerIndex=1015|OwnerPartId=2|FormalType=1|PinConglomerate=58|PinLength=30|Location.X=1200|Location.Y=668|Name=65|Designator=B-65|PinPropagationDelay=0.000000E+000
|RECORD=2|OwnerIndex=1015|OwnerPartId=2|FormalType=1|PinConglomerate=56|PinLength=30|Location.X=1260|Location.Y=668|Name=66|Designator=B-66|PinPropagationDelay=0.000000E+000
|RECORD=2|OwnerIndex=1015|OwnerPartId=2|FormalType=1|PinConglomerate=58|PinLength=30|Location.X=1200|Location.Y=658|Name=67|Designator=B-67|PinPropagationDelay=0.000000E+000
|RECORD=2|OwnerIndex=1015|OwnerPartId=2|FormalType=1|PinConglomerate=56|PinLength=30|Location.X=1260|Location.Y=658|Name=68|Designator=B-68|PinPropagationDelay=0.000000E+000
|RECORD=2|OwnerIndex=1015|OwnerPartId=2|FormalType=1|PinConglomerate=58|PinLength=30|Location.X=1200|Location.Y=648|Name=69|Designator=B-69|PinPropagationDelay=0.000000E+000
|RECORD=2|OwnerIndex=1015|OwnerPartId=2|FormalType=1|PinConglomerate=56|PinLength=30|Location.X=1260|Location.Y=648|Name=70|Designator=B-70|PinPropagationDelay=0.000000E+000
|RECORD=2|OwnerIndex=1015|OwnerPartId=2|FormalType=1|PinConglomerate=58|PinLength=30|Location.X=1200|Location.Y=638|Name=71|Designator=B-71|PinPropagationDelay=0.000000E+000
|RECORD=2|OwnerIndex=1015|OwnerPartId=2|FormalType=1|PinConglomerate=56|PinLength=30|Location.X=1260|Location.Y=638|Name=72|Designator=B-72|PinPropagationDelay=0.000000E+000
|RECORD=2|OwnerIndex=1015|OwnerPartId=2|FormalType=1|PinConglomerate=58|PinLength=30|Location.X=1200|Location.Y=628|Name=73|Designator=B-73|PinPropagationDelay=0.000000E+000
|RECORD=2|OwnerIndex=1015|OwnerPartId=2|FormalType=1|PinConglomerate=56|PinLength=30|Location.X=1260|Location.Y=628|Name=74|Designator=B-74|PinPropagationDelay=0.000000E+000
|RECORD=2|OwnerIndex=1015|OwnerPartId=2|FormalType=1|PinConglomerate=58|PinLength=30|Location.X=1200|Location.Y=618|Name=75|Designator=B-75|PinPropagationDelay=0.000000E+000
|RECORD=2|OwnerIndex=1015|OwnerPartId=2|FormalType=1|PinConglomerate=56|PinLength=30|Location.X=1260|Location.Y=618|Name=76|Designator=B-76|PinPropagationDelay=0.000000E+000
|RECORD=2|OwnerIndex=1015|OwnerPartId=2|FormalType=1|PinConglomerate=58|PinLength=30|Location.X=1200|Location.Y=608|Name=77|Designator=B-77|PinPropagationDelay=0.000000E+000
|RECORD=2|OwnerIndex=1015|OwnerPartId=2|FormalType=1|PinConglomerate=56|PinLength=30|Location.X=1260|Location.Y=608|Name=78|Designator=B-78|PinPropagationDelay=0.000000E+000
|RECORD=2|OwnerIndex=1015|OwnerPartId=2|FormalType=1|PinConglomerate=58|PinLength=30|Location.X=1200|Location.Y=598|Name=79|Designator=B-79|PinPropagationDelay=0.000000E+000
|RECORD=2|OwnerIndex=1015|OwnerPartId=2|FormalType=1|PinConglomerate=56|PinLength=30|Location.X=1260|Location.Y=598|Name=80|Designator=B-80|PinPropagationDelay=0.000000E+000
|RECORD=2|OwnerIndex=1015|OwnerPartId=2|FormalType=1|PinConglomerate=58|PinLength=30|Location.X=1200|Location.Y=588|Name=81|Designator=B-81|PinPropagationDelay=0.000000E+000
|RECORD=2|OwnerIndex=1015|OwnerPartId=2|FormalType=1|PinConglomerate=56|PinLength=30|Location.X=1260|Location.Y=588|Name=82|Designator=B-82|PinPropagationDelay=0.000000E+000
|RECORD=2|OwnerIndex=1015|OwnerPartId=2|FormalType=1|PinConglomerate=58|PinLength=30|Location.X=1200|Location.Y=578|Name=83|Designator=B-83|PinPropagationDelay=0.000000E+000
|RECORD=2|OwnerIndex=1015|OwnerPartId=2|FormalType=1|PinConglomerate=56|PinLength=30|Location.X=1260|Location.Y=578|Name=84|Designator=B-84|PinPropagationDelay=0.000000E+000
|RECORD=14|OwnerIndex=1015|IsNotAccesible=T|IndexInSheet=85|OwnerPartId=3|Location.X=1200|Location.Y=568|Corner.X=1260|Corner.Y=998|Color=128|AreaColor=11599871|IsSolid=T
|RECORD=2|OwnerIndex=1015|OwnerPartId=3|FormalType=1|PinConglomerate=58|PinLength=30|Location.X=1200|Location.Y=988|Name=1|Designator=C-1|PinPropagationDelay=0.000000E+000
|RECORD=2|OwnerIndex=1015|OwnerPartId=3|FormalType=1|PinConglomerate=56|PinLength=30|Location.X=1260|Location.Y=988|Name=2|Designator=C-2|PinPropagationDelay=0.000000E+000
|RECORD=2|OwnerIndex=1015|OwnerPartId=3|FormalType=1|PinConglomerate=58|PinLength=30|Location.X=1200|Location.Y=978|Name=3|Designator=C-3|PinPropagationDelay=0.000000E+000
|RECORD=2|OwnerIndex=1015|OwnerPartId=3|FormalType=1|PinConglomerate=56|PinLength=30|Location.X=1260|Location.Y=978|Name=4|Designator=C-4|PinPropagationDelay=0.000000E+000
|RECORD=2|OwnerIndex=1015|OwnerPartId=3|FormalType=1|PinConglomerate=58|PinLength=30|Location.X=1200|Location.Y=968|Name=5|Designator=C-5|PinPropagationDelay=0.000000E+000
|RECORD=2|OwnerIndex=1015|OwnerPartId=3|FormalType=1|PinConglomerate=56|PinLength=30|Location.X=1260|Location.Y=968|Name=6|Designator=C-6|PinPropagationDelay=0.000000E+000
|RECORD=2|OwnerIndex=1015|OwnerPartId=3|FormalType=1|PinConglomerate=58|PinLength=30|Location.X=1200|Location.Y=958|Name=7|Designator=C-7|PinPropagationDelay=0.000000E+000
|RECORD=2|OwnerIndex=1015|OwnerPartId=3|FormalType=1|PinConglomerate=56|PinLength=30|Location.X=1260|Location.Y=958|Name=8|Designator=C-8|PinPropagationDelay=0.000000E+000
|RECORD=2|OwnerIndex=1015|OwnerPartId=3|FormalType=1|PinConglomerate=58|PinLength=30|Location.X=1200|Location.Y=948|Name=9|Designator=C-9|PinPropagationDelay=0.000000E+000
|RECORD=2|OwnerIndex=1015|OwnerPartId=3|FormalType=1|PinConglomerate=56|PinLength=30|Location.X=1260|Location.Y=948|Name=10|Designator=C-10|PinPropagationDelay=0.000000E+000
|RECORD=2|OwnerIndex=1015|OwnerPartId=3|FormalType=1|PinConglomerate=58|PinLength=30|Location.X=1200|Location.Y=938|Name=11|Designator=C-11|PinPropagationDelay=0.000000E+000
|RECORD=2|OwnerIndex=1015|OwnerPartId=3|FormalType=1|PinConglomerate=56|PinLength=30|Location.X=1260|Location.Y=938|Name=12|Designator=C-12|PinPropagationDelay=0.000000E+000
|RECORD=2|OwnerIndex=1015|OwnerPartId=3|FormalType=1|PinConglomerate=58|PinLength=30|Location.X=1200|Location.Y=928|Name=13|Designator=C-13|PinPropagationDelay=0.000000E+000
|RECORD=2|OwnerIndex=1015|OwnerPartId=3|FormalType=1|PinConglomerate=56|PinLength=30|Location.X=1260|Location.Y=928|Name=14|Designator=C-14|PinPropagationDelay=0.000000E+000
|RECORD=2|OwnerIndex=1015|OwnerPartId=3|FormalType=1|PinConglomerate=58|PinLength=30|Location.X=1200|Location.Y=918|Name=15|Designator=C-15|PinPropagationDelay=0.000000E+000
|RECORD=2|OwnerIndex=1015|OwnerPartId=3|FormalType=1|PinConglomerate=56|PinLength=30|Location.X=1260|Location.Y=918|Name=16|Designator=C-16|PinPropagationDelay=0.000000E+000
|RECORD=2|OwnerIndex=1015|OwnerPartId=3|FormalType=1|PinConglomerate=58|PinLength=30|Location.X=1200|Location.Y=908|Name=17|Designator=C-17|PinPropagationDelay=0.000000E+000
|RECORD=2|OwnerIndex=1015|OwnerPartId=3|FormalType=1|PinConglomerate=56|PinLength=30|Location.X=1260|Location.Y=908|Name=18|Designator=C-18|PinPropagationDelay=0.000000E+000
|RECORD=2|OwnerIndex=1015|OwnerPartId=3|FormalType=1|PinConglomerate=58|PinLength=30|Location.X=1200|Location.Y=898|Name=19|Designator=C-19|PinPropagationDelay=0.000000E+000
|RECORD=2|OwnerIndex=1015|OwnerPartId=3|FormalType=1|PinConglomerate=56|PinLength=30|Location.X=1260|Location.Y=898|Name=20|Designator=C-20|PinPropagationDelay=0.000000E+000
|RECORD=2|OwnerIndex=1015|OwnerPartId=3|FormalType=1|PinConglomerate=58|PinLength=30|Location.X=1200|Location.Y=888|Name=21|Designator=C-21|PinPropagationDelay=0.000000E+000
|RECORD=2|OwnerIndex=1015|OwnerPartId=3|FormalType=1|PinConglomerate=56|PinLength=30|Location.X=1260|Location.Y=888|Name=22|Designator=C-22|PinPropagationDelay=0.000000E+000
|RECORD=2|OwnerIndex=1015|OwnerPartId=3|FormalType=1|PinConglomerate=58|PinLength=30|Location.X=1200|Location.Y=878|Name=23|Designator=C-23|PinPropagationDelay=0.000000E+000
|RECORD=2|OwnerIndex=1015|OwnerPartId=3|FormalType=1|PinConglomerate=56|PinLength=30|Location.X=1260|Location.Y=878|Name=24|Designator=C-24|PinPropagationDelay=0.000000E+000
|RECORD=2|OwnerIndex=1015|OwnerPartId=3|FormalType=1|PinConglomerate=58|PinLength=30|Location.X=1200|Location.Y=868|Name=25|Designator=C-25|PinPropagationDelay=0.000000E+000
|RECORD=2|OwnerIndex=1015|OwnerPartId=3|FormalType=1|PinConglomerate=56|PinLength=30|Location.X=1260|Location.Y=868|Name=26|Designator=C-26|PinPropagationDelay=0.000000E+000
|RECORD=2|OwnerIndex=1015|OwnerPartId=3|FormalType=1|PinConglomerate=58|PinLength=30|Location.X=1200|Location.Y=858|Name=27|Designator=C-27|PinPropagationDelay=0.000000E+000
|RECORD=2|OwnerIndex=1015|OwnerPartId=3|FormalType=1|PinConglomerate=56|PinLength=30|Location.X=1260|Location.Y=858|Name=28|Designator=C-28|PinPropagationDelay=0.000000E+000
|RECORD=2|OwnerIndex=1015|OwnerPartId=3|FormalType=1|PinConglomerate=58|PinLength=30|Location.X=1200|Location.Y=848|Name=29|Designator=C-29|PinPropagationDelay=0.000000E+000
|RECORD=2|OwnerIndex=1015|OwnerPartId=3|FormalType=1|PinConglomerate=56|PinLength=30|Location.X=1260|Location.Y=848|Name=30|Designator=C-30|PinPropagationDelay=0.000000E+000
|RECORD=2|OwnerIndex=1015|OwnerPartId=3|FormalType=1|PinConglomerate=58|PinLength=30|Location.X=1200|Location.Y=838|Name=31|Designator=C-31|PinPropagationDelay=0.000000E+000
|RECORD=2|OwnerIndex=1015|OwnerPartId=3|FormalType=1|PinConglomerate=56|PinLength=30|Location.X=1260|Location.Y=838|Name=32|Designator=C-32|PinPropagationDelay=0.000000E+000
|RECORD=2|OwnerIndex=1015|OwnerPartId=3|FormalType=1|PinConglomerate=58|PinLength=30|Location.X=1200|Location.Y=828|Name=33|Designator=C-33|PinPropagationDelay=0.000000E+000
|RECORD=2|OwnerIndex=1015|OwnerPartId=3|FormalType=1|PinConglomerate=56|PinLength=30|Location.X=1260|Location.Y=828|Name=34|Designator=C-34|PinPropagationDelay=0.000000E+000
|RECORD=2|OwnerIndex=1015|OwnerPartId=3|FormalType=1|PinConglomerate=58|PinLength=30|Location.X=1200|Location.Y=818|Name=35|Designator=C-35|PinPropagationDelay=0.000000E+000
|RECORD=2|OwnerIndex=1015|OwnerPartId=3|FormalType=1|PinConglomerate=56|PinLength=30|Location.X=1260|Location.Y=818|Name=36|Designator=C-36|PinPropagationDelay=0.000000E+000
|RECORD=2|OwnerIndex=1015|OwnerPartId=3|FormalType=1|PinConglomerate=58|PinLength=30|Location.X=1200|Location.Y=808|Name=37|Designator=C-37|PinPropagationDelay=0.000000E+000
|RECORD=2|OwnerIndex=1015|OwnerPartId=3|FormalType=1|PinConglomerate=56|PinLength=30|Location.X=1260|Location.Y=808|Name=38|Designator=C-38|PinPropagationDelay=0.000000E+000
|RECORD=2|OwnerIndex=1015|OwnerPartId=3|FormalType=1|PinConglomerate=58|PinLength=30|Location.X=1200|Location.Y=798|Name=39|Designator=C-39|PinPropagationDelay=0.000000E+000
|RECORD=2|OwnerIndex=1015|OwnerPartId=3|FormalType=1|PinConglomerate=56|PinLength=30|Location.X=1260|Location.Y=798|Name=40|Designator=C-40|PinPropagationDelay=0.000000E+000
|RECORD=2|OwnerIndex=1015|OwnerPartId=3|FormalType=1|PinConglomerate=58|PinLength=30|Location.X=1200|Location.Y=788|Name=41|Designator=C-41|PinPropagationDelay=0.000000E+000
|RECORD=2|OwnerIndex=1015|OwnerPartId=3|FormalType=1|PinConglomerate=56|PinLength=30|Location.X=1260|Location.Y=788|Name=42|Designator=C-42|PinPropagationDelay=0.000000E+000
|RECORD=2|OwnerIndex=1015|OwnerPartId=3|FormalType=1|PinConglomerate=58|PinLength=30|Location.X=1200|Location.Y=778|Name=43|Designator=C-43|PinPropagationDelay=0.000000E+000
|RECORD=2|OwnerIndex=1015|OwnerPartId=3|FormalType=1|PinConglomerate=56|PinLength=30|Location.X=1260|Location.Y=778|Name=44|Designator=C-44|PinPropagationDelay=0.000000E+000
|RECORD=2|OwnerIndex=1015|OwnerPartId=3|FormalType=1|PinConglomerate=58|PinLength=30|Location.X=1200|Location.Y=768|Name=45|Designator=C-45|PinPropagationDelay=0.000000E+000
|RECORD=2|OwnerIndex=1015|OwnerPartId=3|FormalType=1|PinConglomerate=56|PinLength=30|Location.X=1260|Location.Y=768|Name=46|Designator=C-46|PinPropagationDelay=0.000000E+000
|RECORD=2|OwnerIndex=1015|OwnerPartId=3|FormalType=1|PinConglomerate=58|PinLength=30|Location.X=1200|Location.Y=758|Name=47|Designator=C-47|PinPropagationDelay=0.000000E+000
|RECORD=2|OwnerIndex=1015|OwnerPartId=3|FormalType=1|PinConglomerate=56|PinLength=30|Location.X=1260|Location.Y=758|Name=48|Designator=C-48|PinPropagationDelay=0.000000E+000
|RECORD=2|OwnerIndex=1015|OwnerPartId=3|FormalType=1|PinConglomerate=58|PinLength=30|Location.X=1200|Location.Y=748|Name=49|Designator=C-49|PinPropagationDelay=0.000000E+000
|RECORD=2|OwnerIndex=1015|OwnerPartId=3|FormalType=1|PinConglomerate=56|PinLength=30|Location.X=1260|Location.Y=748|Name=50|Designator=C-50|PinPropagationDelay=0.000000E+000
|RECORD=2|OwnerIndex=1015|OwnerPartId=3|FormalType=1|PinConglomerate=58|PinLength=30|Location.X=1200|Location.Y=738|Name=51|Designator=C-51|PinPropagationDelay=0.000000E+000
|RECORD=2|OwnerIndex=1015|OwnerPartId=3|FormalType=1|PinConglomerate=56|PinLength=30|Location.X=1260|Location.Y=738|Name=52|Designator=C-52|PinPropagationDelay=0.000000E+000
|RECORD=2|OwnerIndex=1015|OwnerPartId=3|FormalType=1|PinConglomerate=58|PinLength=30|Location.X=1200|Location.Y=728|Name=53|Designator=C-53|PinPropagationDelay=0.000000E+000
|RECORD=2|OwnerIndex=1015|OwnerPartId=3|FormalType=1|PinConglomerate=56|PinLength=30|Location.X=1260|Location.Y=728|Name=54|Designator=C-54|PinPropagationDelay=0.000000E+000
|RECORD=2|OwnerIndex=1015|OwnerPartId=3|FormalType=1|PinConglomerate=58|PinLength=30|Location.X=1200|Location.Y=718|Name=55|Designator=C-55|PinPropagationDelay=0.000000E+000
|RECORD=2|OwnerIndex=1015|OwnerPartId=3|FormalType=1|PinConglomerate=56|PinLength=30|Location.X=1260|Location.Y=718|Name=56|Designator=C-56|PinPropagationDelay=0.000000E+000
|RECORD=2|OwnerIndex=1015|OwnerPartId=3|FormalType=1|PinConglomerate=58|PinLength=30|Location.X=1200|Location.Y=708|Name=57|Designator=C-57|PinPropagationDelay=0.000000E+000
|RECORD=2|OwnerIndex=1015|OwnerPartId=3|FormalType=1|PinConglomerate=56|PinLength=30|Location.X=1260|Location.Y=708|Name=58|Designator=C-58|PinPropagationDelay=0.000000E+000
|RECORD=2|OwnerIndex=1015|OwnerPartId=3|FormalType=1|PinConglomerate=58|PinLength=30|Location.X=1200|Location.Y=698|Name=59|Designator=C-59|PinPropagationDelay=0.000000E+000
|RECORD=2|OwnerIndex=1015|OwnerPartId=3|FormalType=1|PinConglomerate=56|PinLength=30|Location.X=1260|Location.Y=698|Name=60|Designator=C-60|PinPropagationDelay=0.000000E+000
|RECORD=2|OwnerIndex=1015|OwnerPartId=3|FormalType=1|PinConglomerate=58|PinLength=30|Location.X=1200|Location.Y=688|Name=61|Designator=C-61|PinPropagationDelay=0.000000E+000
|RECORD=2|OwnerIndex=1015|OwnerPartId=3|FormalType=1|PinConglomerate=56|PinLength=30|Location.X=1260|Location.Y=688|Name=62|Designator=C-62|PinPropagationDelay=0.000000E+000
|RECORD=2|OwnerIndex=1015|OwnerPartId=3|FormalType=1|PinConglomerate=58|PinLength=30|Location.X=1200|Location.Y=678|Name=63|Designator=C-63|PinPropagationDelay=0.000000E+000
|RECORD=2|OwnerIndex=1015|OwnerPartId=3|FormalType=1|PinConglomerate=56|PinLength=30|Location.X=1260|Location.Y=678|Name=64|Designator=C-64|PinPropagationDelay=0.000000E+000
|RECORD=2|OwnerIndex=1015|OwnerPartId=3|FormalType=1|PinConglomerate=58|PinLength=30|Location.X=1200|Location.Y=668|Name=65|Designator=C-65|PinPropagationDelay=0.000000E+000
|RECORD=2|OwnerIndex=1015|OwnerPartId=3|FormalType=1|PinConglomerate=56|PinLength=30|Location.X=1260|Location.Y=668|Name=66|Designator=C-66|PinPropagationDelay=0.000000E+000
|RECORD=2|OwnerIndex=1015|OwnerPartId=3|FormalType=1|PinConglomerate=58|PinLength=30|Location.X=1200|Location.Y=658|Name=67|Designator=C-67|PinPropagationDelay=0.000000E+000
|RECORD=2|OwnerIndex=1015|OwnerPartId=3|FormalType=1|PinConglomerate=56|PinLength=30|Location.X=1260|Location.Y=658|Name=68|Designator=C-68|PinPropagationDelay=0.000000E+000
|RECORD=2|OwnerIndex=1015|OwnerPartId=3|FormalType=1|PinConglomerate=58|PinLength=30|Location.X=1200|Location.Y=648|Name=69|Designator=C-69|PinPropagationDelay=0.000000E+000
|RECORD=2|OwnerIndex=1015|OwnerPartId=3|FormalType=1|PinConglomerate=56|PinLength=30|Location.X=1260|Location.Y=648|Name=70|Designator=C-70|PinPropagationDelay=0.000000E+000
|RECORD=2|OwnerIndex=1015|OwnerPartId=3|FormalType=1|PinConglomerate=58|PinLength=30|Location.X=1200|Location.Y=638|Name=71|Designator=C-71|PinPropagationDelay=0.000000E+000
|RECORD=2|OwnerIndex=1015|OwnerPartId=3|FormalType=1|PinConglomerate=56|PinLength=30|Location.X=1260|Location.Y=638|Name=72|Designator=C-72|PinPropagationDelay=0.000000E+000
|RECORD=2|OwnerIndex=1015|OwnerPartId=3|FormalType=1|PinConglomerate=58|PinLength=30|Location.X=1200|Location.Y=628|Name=73|Designator=C-73|PinPropagationDelay=0.000000E+000
|RECORD=2|OwnerIndex=1015|OwnerPartId=3|FormalType=1|PinConglomerate=56|PinLength=30|Location.X=1260|Location.Y=628|Name=74|Designator=C-74|PinPropagationDelay=0.000000E+000
|RECORD=2|OwnerIndex=1015|OwnerPartId=3|FormalType=1|PinConglomerate=58|PinLength=30|Location.X=1200|Location.Y=618|Name=75|Designator=C-75|PinPropagationDelay=0.000000E+000
|RECORD=2|OwnerIndex=1015|OwnerPartId=3|FormalType=1|PinConglomerate=56|PinLength=30|Location.X=1260|Location.Y=618|Name=76|Designator=C-76|PinPropagationDelay=0.000000E+000
|RECORD=2|OwnerIndex=1015|OwnerPartId=3|FormalType=1|PinConglomerate=58|PinLength=30|Location.X=1200|Location.Y=608|Name=77|Designator=C-77|PinPropagationDelay=0.000000E+000
|RECORD=2|OwnerIndex=1015|OwnerPartId=3|FormalType=1|PinConglomerate=56|PinLength=30|Location.X=1260|Location.Y=608|Name=78|Designator=C-78|PinPropagationDelay=0.000000E+000
|RECORD=2|OwnerIndex=1015|OwnerPartId=3|FormalType=1|PinConglomerate=58|PinLength=30|Location.X=1200|Location.Y=598|Name=79|Designator=C-79|PinPropagationDelay=0.000000E+000
|RECORD=2|OwnerIndex=1015|OwnerPartId=3|FormalType=1|PinConglomerate=56|PinLength=30|Location.X=1260|Location.Y=598|Name=80|Designator=C-80|PinPropagationDelay=0.000000E+000
|RECORD=2|OwnerIndex=1015|OwnerPartId=3|FormalType=1|PinConglomerate=58|PinLength=30|Location.X=1200|Location.Y=588|Name=81|Designator=C-81|PinPropagationDelay=0.000000E+000
|RECORD=2|OwnerIndex=1015|OwnerPartId=3|FormalType=1|PinConglomerate=56|PinLength=30|Location.X=1260|Location.Y=588|Name=82|Designator=C-82|PinPropagationDelay=0.000000E+000
|RECORD=2|OwnerIndex=1015|OwnerPartId=3|FormalType=1|PinConglomerate=58|PinLength=30|Location.X=1200|Location.Y=578|Name=83|Designator=C-83|PinPropagationDelay=0.000000E+000
|RECORD=2|OwnerIndex=1015|OwnerPartId=3|FormalType=1|PinConglomerate=56|PinLength=30|Location.X=1260|Location.Y=578|Name=84|Designator=C-84|PinPropagationDelay=0.000000E+000
|RECORD=14|OwnerIndex=1015|IsNotAccesible=T|IndexInSheet=170|OwnerPartId=4|Location.X=1200|Location.Y=568|Corner.X=1260|Corner.Y=998|Color=128|AreaColor=11599871|IsSolid=T
|RECORD=2|OwnerIndex=1015|OwnerPartId=4|FormalType=1|PinConglomerate=58|PinLength=30|Location.X=1200|Location.Y=988|Name=1|Designator=D-1|PinPropagationDelay=0.000000E+000
|RECORD=2|OwnerIndex=1015|OwnerPartId=4|FormalType=1|PinConglomerate=56|PinLength=30|Location.X=1260|Location.Y=988|Name=2|Designator=D-2|PinPropagationDelay=0.000000E+000
|RECORD=2|OwnerIndex=1015|OwnerPartId=4|FormalType=1|PinConglomerate=58|PinLength=30|Location.X=1200|Location.Y=978|Name=3|Designator=D-3|PinPropagationDelay=0.000000E+000
|RECORD=2|OwnerIndex=1015|OwnerPartId=4|FormalType=1|PinConglomerate=56|PinLength=30|Location.X=1260|Location.Y=978|Name=4|Designator=D-4|PinPropagationDelay=0.000000E+000
|RECORD=2|OwnerIndex=1015|OwnerPartId=4|FormalType=1|PinConglomerate=58|PinLength=30|Location.X=1200|Location.Y=968|Name=5|Designator=D-5|PinPropagationDelay=0.000000E+000
|RECORD=2|OwnerIndex=1015|OwnerPartId=4|FormalType=1|PinConglomerate=56|PinLength=30|Location.X=1260|Location.Y=968|Name=6|Designator=D-6|PinPropagationDelay=0.000000E+000
|RECORD=2|OwnerIndex=1015|OwnerPartId=4|FormalType=1|PinConglomerate=58|PinLength=30|Location.X=1200|Location.Y=958|Name=7|Designator=D-7|PinPropagationDelay=0.000000E+000
|RECORD=2|OwnerIndex=1015|OwnerPartId=4|FormalType=1|PinConglomerate=56|PinLength=30|Location.X=1260|Location.Y=958|Name=8|Designator=D-8|PinPropagationDelay=0.000000E+000
|RECORD=2|OwnerIndex=1015|OwnerPartId=4|FormalType=1|PinConglomerate=58|PinLength=30|Location.X=1200|Location.Y=948|Name=9|Designator=D-9|PinPropagationDelay=0.000000E+000
|RECORD=2|OwnerIndex=1015|OwnerPartId=4|FormalType=1|PinConglomerate=56|PinLength=30|Location.X=1260|Location.Y=948|Name=10|Designator=D-10|PinPropagationDelay=0.000000E+000
|RECORD=2|OwnerIndex=1015|OwnerPartId=4|FormalType=1|PinConglomerate=58|PinLength=30|Location.X=1200|Location.Y=938|Name=11|Designator=D-11|PinPropagationDelay=0.000000E+000
|RECORD=2|OwnerIndex=1015|OwnerPartId=4|FormalType=1|PinConglomerate=56|PinLength=30|Location.X=1260|Location.Y=938|Name=12|Designator=D-12|PinPropagationDelay=0.000000E+000
|RECORD=2|OwnerIndex=1015|OwnerPartId=4|FormalType=1|PinConglomerate=58|PinLength=30|Location.X=1200|Location.Y=928|Name=13|Designator=D-13|PinPropagationDelay=0.000000E+000
|RECORD=2|OwnerIndex=1015|OwnerPartId=4|FormalType=1|PinConglomerate=56|PinLength=30|Location.X=1260|Location.Y=928|Name=14|Designator=D-14|PinPropagationDelay=0.000000E+000
|RECORD=2|OwnerIndex=1015|OwnerPartId=4|FormalType=1|PinConglomerate=58|PinLength=30|Location.X=1200|Location.Y=918|Name=15|Designator=D-15|PinPropagationDelay=0.000000E+000
|RECORD=2|OwnerIndex=1015|OwnerPartId=4|FormalType=1|PinConglomerate=56|PinLength=30|Location.X=1260|Location.Y=918|Name=16|Designator=D-16|PinPropagationDelay=0.000000E+000
|RECORD=2|OwnerIndex=1015|OwnerPartId=4|FormalType=1|PinConglomerate=58|PinLength=30|Location.X=1200|Location.Y=908|Name=17|Designator=D-17|PinPropagationDelay=0.000000E+000
|RECORD=2|OwnerIndex=1015|OwnerPartId=4|FormalType=1|PinConglomerate=56|PinLength=30|Location.X=1260|Location.Y=908|Name=18|Designator=D-18|PinPropagationDelay=0.000000E+000
|RECORD=2|OwnerIndex=1015|OwnerPartId=4|FormalType=1|PinConglomerate=58|PinLength=30|Location.X=1200|Location.Y=898|Name=19|Designator=D-19|PinPropagationDelay=0.000000E+000
|RECORD=2|OwnerIndex=1015|OwnerPartId=4|FormalType=1|PinConglomerate=56|PinLength=30|Location.X=1260|Location.Y=898|Name=20|Designator=D-20|PinPropagationDelay=0.000000E+000
|RECORD=2|OwnerIndex=1015|OwnerPartId=4|FormalType=1|PinConglomerate=58|PinLength=30|Location.X=1200|Location.Y=888|Name=21|Designator=D-21|PinPropagationDelay=0.000000E+000
|RECORD=2|OwnerIndex=1015|OwnerPartId=4|FormalType=1|PinConglomerate=56|PinLength=30|Location.X=1260|Location.Y=888|Name=22|Designator=D-22|PinPropagationDelay=0.000000E+000
|RECORD=2|OwnerIndex=1015|OwnerPartId=4|FormalType=1|PinConglomerate=58|PinLength=30|Location.X=1200|Location.Y=878|Name=23|Designator=D-23|PinPropagationDelay=0.000000E+000
|RECORD=2|OwnerIndex=1015|OwnerPartId=4|FormalType=1|PinConglomerate=56|PinLength=30|Location.X=1260|Location.Y=878|Name=24|Designator=D-24|PinPropagationDelay=0.000000E+000
|RECORD=2|OwnerIndex=1015|OwnerPartId=4|FormalType=1|PinConglomerate=58|PinLength=30|Location.X=1200|Location.Y=868|Name=25|Designator=D-25|PinPropagationDelay=0.000000E+000
|RECORD=2|OwnerIndex=1015|OwnerPartId=4|FormalType=1|PinConglomerate=56|PinLength=30|Location.X=1260|Location.Y=868|Name=26|Designator=D-26|PinPropagationDelay=0.000000E+000
|RECORD=2|OwnerIndex=1015|OwnerPartId=4|FormalType=1|PinConglomerate=58|PinLength=30|Location.X=1200|Location.Y=858|Name=27|Designator=D-27|PinPropagationDelay=0.000000E+000
|RECORD=2|OwnerIndex=1015|OwnerPartId=4|FormalType=1|PinConglomerate=56|PinLength=30|Location.X=1260|Location.Y=858|Name=28|Designator=D-28|PinPropagationDelay=0.000000E+000
|RECORD=2|OwnerIndex=1015|OwnerPartId=4|FormalType=1|PinConglomerate=58|PinLength=30|Location.X=1200|Location.Y=848|Name=29|Designator=D-29|PinPropagationDelay=0.000000E+000
|RECORD=2|OwnerIndex=1015|OwnerPartId=4|FormalType=1|PinConglomerate=56|PinLength=30|Location.X=1260|Location.Y=848|Name=30|Designator=D-30|PinPropagationDelay=0.000000E+000
|RECORD=2|OwnerIndex=1015|OwnerPartId=4|FormalType=1|PinConglomerate=58|PinLength=30|Location.X=1200|Location.Y=838|Name=31|Designator=D-31|PinPropagationDelay=0.000000E+000
|RECORD=2|OwnerIndex=1015|OwnerPartId=4|FormalType=1|PinConglomerate=56|PinLength=30|Location.X=1260|Location.Y=838|Name=32|Designator=D-32|PinPropagationDelay=0.000000E+000
|RECORD=2|OwnerIndex=1015|OwnerPartId=4|FormalType=1|PinConglomerate=58|PinLength=30|Location.X=1200|Location.Y=828|Name=33|Designator=D-33|PinPropagationDelay=0.000000E+000
|RECORD=2|OwnerIndex=1015|OwnerPartId=4|FormalType=1|PinConglomerate=56|PinLength=30|Location.X=1260|Location.Y=828|Name=34|Designator=D-34|PinPropagationDelay=0.000000E+000
|RECORD=2|OwnerIndex=1015|OwnerPartId=4|FormalType=1|PinConglomerate=58|PinLength=30|Location.X=1200|Location.Y=818|Name=35|Designator=D-35|PinPropagationDelay=0.000000E+000
|RECORD=2|OwnerIndex=1015|OwnerPartId=4|FormalType=1|PinConglomerate=56|PinLength=30|Location.X=1260|Location.Y=818|Name=36|Designator=D-36|PinPropagationDelay=0.000000E+000
|RECORD=2|OwnerIndex=1015|OwnerPartId=4|FormalType=1|PinConglomerate=58|PinLength=30|Location.X=1200|Location.Y=808|Name=37|Designator=D-37|PinPropagationDelay=0.000000E+000
|RECORD=2|OwnerIndex=1015|OwnerPartId=4|FormalType=1|PinConglomerate=56|PinLength=30|Location.X=1260|Location.Y=808|Name=38|Designator=D-38|PinPropagationDelay=0.000000E+000
|RECORD=2|OwnerIndex=1015|OwnerPartId=4|FormalType=1|PinConglomerate=58|PinLength=30|Location.X=1200|Location.Y=798|Name=39|Designator=D-39|PinPropagationDelay=0.000000E+000
|RECORD=2|OwnerIndex=1015|OwnerPartId=4|FormalType=1|PinConglomerate=56|PinLength=30|Location.X=1260|Location.Y=798|Name=40|Designator=D-40|PinPropagationDelay=0.000000E+000
|RECORD=2|OwnerIndex=1015|OwnerPartId=4|FormalType=1|PinConglomerate=58|PinLength=30|Location.X=1200|Location.Y=788|Name=41|Designator=D-41|PinPropagationDelay=0.000000E+000
|RECORD=2|OwnerIndex=1015|OwnerPartId=4|FormalType=1|PinConglomerate=56|PinLength=30|Location.X=1260|Location.Y=788|Name=42|Designator=D-42|PinPropagationDelay=0.000000E+000
|RECORD=2|OwnerIndex=1015|OwnerPartId=4|FormalType=1|PinConglomerate=58|PinLength=30|Location.X=1200|Location.Y=778|Name=43|Designator=D-43|PinPropagationDelay=0.000000E+000
|RECORD=2|OwnerIndex=1015|OwnerPartId=4|FormalType=1|PinConglomerate=56|PinLength=30|Location.X=1260|Location.Y=778|Name=44|Designator=D-44|PinPropagationDelay=0.000000E+000
|RECORD=2|OwnerIndex=1015|OwnerPartId=4|FormalType=1|PinConglomerate=58|PinLength=30|Location.X=1200|Location.Y=768|Name=45|Designator=D-45|PinPropagationDelay=0.000000E+000
|RECORD=2|OwnerIndex=1015|OwnerPartId=4|FormalType=1|PinConglomerate=56|PinLength=30|Location.X=1260|Location.Y=768|Name=46|Designator=D-46|PinPropagationDelay=0.000000E+000
|RECORD=2|OwnerIndex=1015|OwnerPartId=4|FormalType=1|PinConglomerate=58|PinLength=30|Location.X=1200|Location.Y=758|Name=47|Designator=D-47|PinPropagationDelay=0.000000E+000
|RECORD=2|OwnerIndex=1015|OwnerPartId=4|FormalType=1|PinConglomerate=56|PinLength=30|Location.X=1260|Location.Y=758|Name=48|Designator=D-48|PinPropagationDelay=0.000000E+000
|RECORD=2|OwnerIndex=1015|OwnerPartId=4|FormalType=1|PinConglomerate=58|PinLength=30|Location.X=1200|Location.Y=748|Name=49|Designator=D-49|PinPropagationDelay=0.000000E+000
|RECORD=2|OwnerIndex=1015|OwnerPartId=4|FormalType=1|PinConglomerate=56|PinLength=30|Location.X=1260|Location.Y=748|Name=50|Designator=D-50|PinPropagationDelay=0.000000E+000
|RECORD=2|OwnerIndex=1015|OwnerPartId=4|FormalType=1|PinConglomerate=58|PinLength=30|Location.X=1200|Location.Y=738|Name=51|Designator=D-51|PinPropagationDelay=0.000000E+000
|RECORD=2|OwnerIndex=1015|OwnerPartId=4|FormalType=1|PinConglomerate=56|PinLength=30|Location.X=1260|Location.Y=738|Name=52|Designator=D-52|PinPropagationDelay=0.000000E+000
|RECORD=2|OwnerIndex=1015|OwnerPartId=4|FormalType=1|PinConglomerate=58|PinLength=30|Location.X=1200|Location.Y=728|Name=53|Designator=D-53|PinPropagationDelay=0.000000E+000
|RECORD=2|OwnerIndex=1015|OwnerPartId=4|FormalType=1|PinConglomerate=56|PinLength=30|Location.X=1260|Location.Y=728|Name=54|Designator=D-54|PinPropagationDelay=0.000000E+000
|RECORD=2|OwnerIndex=1015|OwnerPartId=4|FormalType=1|PinConglomerate=58|PinLength=30|Location.X=1200|Location.Y=718|Name=55|Designator=D-55|PinPropagationDelay=0.000000E+000
|RECORD=2|OwnerIndex=1015|OwnerPartId=4|FormalType=1|PinConglomerate=56|PinLength=30|Location.X=1260|Location.Y=718|Name=56|Designator=D-56|PinPropagationDelay=0.000000E+000
|RECORD=2|OwnerIndex=1015|OwnerPartId=4|FormalType=1|PinConglomerate=58|PinLength=30|Location.X=1200|Location.Y=708|Name=57|Designator=D-57|PinPropagationDelay=0.000000E+000
|RECORD=2|OwnerIndex=1015|OwnerPartId=4|FormalType=1|PinConglomerate=56|PinLength=30|Location.X=1260|Location.Y=708|Name=58|Designator=D-58|PinPropagationDelay=0.000000E+000
|RECORD=2|OwnerIndex=1015|OwnerPartId=4|FormalType=1|PinConglomerate=58|PinLength=30|Location.X=1200|Location.Y=698|Name=59|Designator=D-59|PinPropagationDelay=0.000000E+000
|RECORD=2|OwnerIndex=1015|OwnerPartId=4|FormalType=1|PinConglomerate=56|PinLength=30|Location.X=1260|Location.Y=698|Name=60|Designator=D-60|PinPropagationDelay=0.000000E+000
|RECORD=2|OwnerIndex=1015|OwnerPartId=4|FormalType=1|PinConglomerate=58|PinLength=30|Location.X=1200|Location.Y=688|Name=61|Designator=D-61|PinPropagationDelay=0.000000E+000
|RECORD=2|OwnerIndex=1015|OwnerPartId=4|FormalType=1|PinConglomerate=56|PinLength=30|Location.X=1260|Location.Y=688|Name=62|Designator=D-62|PinPropagationDelay=0.000000E+000
|RECORD=2|OwnerIndex=1015|OwnerPartId=4|FormalType=1|PinConglomerate=58|PinLength=30|Location.X=1200|Location.Y=678|Name=63|Designator=D-63|PinPropagationDelay=0.000000E+000
|RECORD=2|OwnerIndex=1015|OwnerPartId=4|FormalType=1|PinConglomerate=56|PinLength=30|Location.X=1260|Location.Y=678|Name=64|Designator=D-64|PinPropagationDelay=0.000000E+000
|RECORD=2|OwnerIndex=1015|OwnerPartId=4|FormalType=1|PinConglomerate=58|PinLength=30|Location.X=1200|Location.Y=668|Name=65|Designator=D-65|PinPropagationDelay=0.000000E+000
|RECORD=2|OwnerIndex=1015|OwnerPartId=4|FormalType=1|PinConglomerate=56|PinLength=30|Location.X=1260|Location.Y=668|Name=66|Designator=D-66|PinPropagationDelay=0.000000E+000
|RECORD=2|OwnerIndex=1015|OwnerPartId=4|FormalType=1|PinConglomerate=58|PinLength=30|Location.X=1200|Location.Y=658|Name=67|Designator=D-67|PinPropagationDelay=0.000000E+000
|RECORD=2|OwnerIndex=1015|OwnerPartId=4|FormalType=1|PinConglomerate=56|PinLength=30|Location.X=1260|Location.Y=658|Name=68|Designator=D-68|PinPropagationDelay=0.000000E+000
|RECORD=2|OwnerIndex=1015|OwnerPartId=4|FormalType=1|PinConglomerate=58|PinLength=30|Location.X=1200|Location.Y=648|Name=69|Designator=D-69|PinPropagationDelay=0.000000E+000
|RECORD=2|OwnerIndex=1015|OwnerPartId=4|FormalType=1|PinConglomerate=56|PinLength=30|Location.X=1260|Location.Y=648|Name=70|Designator=D-70|PinPropagationDelay=0.000000E+000
|RECORD=2|OwnerIndex=1015|OwnerPartId=4|FormalType=1|PinConglomerate=58|PinLength=30|Location.X=1200|Location.Y=638|Name=71|Designator=D-71|PinPropagationDelay=0.000000E+000
|RECORD=2|OwnerIndex=1015|OwnerPartId=4|FormalType=1|PinConglomerate=56|PinLength=30|Location.X=1260|Location.Y=638|Name=72|Designator=D-72|PinPropagationDelay=0.000000E+000
|RECORD=2|OwnerIndex=1015|OwnerPartId=4|FormalType=1|PinConglomerate=58|PinLength=30|Location.X=1200|Location.Y=628|Name=73|Designator=D-73|PinPropagationDelay=0.000000E+000
|RECORD=2|OwnerIndex=1015|OwnerPartId=4|FormalType=1|PinConglomerate=56|PinLength=30|Location.X=1260|Location.Y=628|Name=74|Designator=D-74|PinPropagationDelay=0.000000E+000
|RECORD=2|OwnerIndex=1015|OwnerPartId=4|FormalType=1|PinConglomerate=58|PinLength=30|Location.X=1200|Location.Y=618|Name=75|Designator=D-75|PinPropagationDelay=0.000000E+000
|RECORD=2|OwnerIndex=1015|OwnerPartId=4|FormalType=1|PinConglomerate=56|PinLength=30|Location.X=1260|Location.Y=618|Name=76|Designator=D-76|PinPropagationDelay=0.000000E+000
|RECORD=2|OwnerIndex=1015|OwnerPartId=4|FormalType=1|PinConglomerate=58|PinLength=30|Location.X=1200|Location.Y=608|Name=77|Designator=D-77|PinPropagationDelay=0.000000E+000
|RECORD=2|OwnerIndex=1015|OwnerPartId=4|FormalType=1|PinConglomerate=56|PinLength=30|Location.X=1260|Location.Y=608|Name=78|Designator=D-78|PinPropagationDelay=0.000000E+000
|RECORD=2|OwnerIndex=1015|OwnerPartId=4|FormalType=1|PinConglomerate=58|PinLength=30|Location.X=1200|Location.Y=598|Name=79|Designator=D-79|PinPropagationDelay=0.000000E+000
|RECORD=2|OwnerIndex=1015|OwnerPartId=4|FormalType=1|PinConglomerate=56|PinLength=30|Location.X=1260|Location.Y=598|Name=80|Designator=D-80|PinPropagationDelay=0.000000E+000
|RECORD=2|OwnerIndex=1015|OwnerPartId=4|FormalType=1|PinConglomerate=58|PinLength=30|Location.X=1200|Location.Y=588|Name=81|Designator=D-81|PinPropagationDelay=0.000000E+000
|RECORD=2|OwnerIndex=1015|OwnerPartId=4|FormalType=1|PinConglomerate=56|PinLength=30|Location.X=1260|Location.Y=588|Name=82|Designator=D-82|PinPropagationDelay=0.000000E+000
|RECORD=2|OwnerIndex=1015|OwnerPartId=4|FormalType=1|PinConglomerate=58|PinLength=30|Location.X=1200|Location.Y=578|Name=83|Designator=D-83|PinPropagationDelay=0.000000E+000
|RECORD=2|OwnerIndex=1015|OwnerPartId=4|FormalType=1|PinConglomerate=56|PinLength=30|Location.X=1260|Location.Y=578|Name=84|Designator=D-84|PinPropagationDelay=0.000000E+000
|RECORD=14|OwnerIndex=1015|IsNotAccesible=T|IndexInSheet=255|OwnerPartId=1|Location.X=1200|Location.Y=568|Corner.X=1260|Corner.Y=998|Color=128|AreaColor=11599871|IsSolid=T
|RECORD=2|OwnerIndex=1015|OwnerPartId=1|FormalType=1|PinConglomerate=58|PinLength=30|Location.X=1200|Location.Y=988|Name=1|Designator=A-1|PinPropagationDelay=0.000000E+000
|RECORD=2|OwnerIndex=1015|OwnerPartId=1|FormalType=1|PinConglomerate=56|PinLength=30|Location.X=1260|Location.Y=988|Name=2|Designator=A-2|PinPropagationDelay=0.000000E+000
|RECORD=2|OwnerIndex=1015|OwnerPartId=1|FormalType=1|PinConglomerate=58|PinLength=30|Location.X=1200|Location.Y=978|Name=3|Designator=A-3|PinPropagationDelay=0.000000E+000
|RECORD=2|OwnerIndex=1015|OwnerPartId=1|FormalType=1|PinConglomerate=56|PinLength=30|Location.X=1260|Location.Y=978|Name=4|Designator=A-4|PinPropagationDelay=0.000000E+000
|RECORD=2|OwnerIndex=1015|OwnerPartId=1|FormalType=1|PinConglomerate=58|PinLength=30|Location.X=1200|Location.Y=968|Name=5|Designator=A-5|PinPropagationDelay=0.000000E+000
|RECORD=2|OwnerIndex=1015|OwnerPartId=1|FormalType=1|PinConglomerate=56|PinLength=30|Location.X=1260|Location.Y=968|Name=6|Designator=A-6|PinPropagationDelay=0.000000E+000
|RECORD=2|OwnerIndex=1015|OwnerPartId=1|FormalType=1|PinConglomerate=58|PinLength=30|Location.X=1200|Location.Y=958|Name=7|Designator=A-7|PinPropagationDelay=0.000000E+000
|RECORD=2|OwnerIndex=1015|OwnerPartId=1|FormalType=1|PinConglomerate=56|PinLength=30|Location.X=1260|Location.Y=958|Name=8|Designator=A-8|PinPropagationDelay=0.000000E+000
|RECORD=2|OwnerIndex=1015|OwnerPartId=1|FormalType=1|PinConglomerate=58|PinLength=30|Location.X=1200|Location.Y=948|Name=9|Designator=A-9|PinPropagationDelay=0.000000E+000
|RECORD=2|OwnerIndex=1015|OwnerPartId=1|FormalType=1|PinConglomerate=56|PinLength=30|Location.X=1260|Location.Y=948|Name=10|Designator=A-10|PinPropagationDelay=0.000000E+000
|RECORD=2|OwnerIndex=1015|OwnerPartId=1|FormalType=1|PinConglomerate=58|PinLength=30|Location.X=1200|Location.Y=938|Name=11|Designator=A-11|PinPropagationDelay=0.000000E+000
|RECORD=2|OwnerIndex=1015|OwnerPartId=1|FormalType=1|PinConglomerate=56|PinLength=30|Location.X=1260|Location.Y=938|Name=12|Designator=A-12|PinPropagationDelay=0.000000E+000
|RECORD=2|OwnerIndex=1015|OwnerPartId=1|FormalType=1|PinConglomerate=58|PinLength=30|Location.X=1200|Location.Y=928|Name=13|Designator=A-13|PinPropagationDelay=0.000000E+000
|RECORD=2|OwnerIndex=1015|OwnerPartId=1|FormalType=1|PinConglomerate=56|PinLength=30|Location.X=1260|Location.Y=928|Name=14|Designator=A-14|PinPropagationDelay=0.000000E+000
|RECORD=2|OwnerIndex=1015|OwnerPartId=1|FormalType=1|PinConglomerate=58|PinLength=30|Location.X=1200|Location.Y=918|Name=15|Designator=A-15|PinPropagationDelay=0.000000E+000
|RECORD=2|OwnerIndex=1015|OwnerPartId=1|FormalType=1|PinConglomerate=56|PinLength=30|Location.X=1260|Location.Y=918|Name=16|Designator=A-16|PinPropagationDelay=0.000000E+000
|RECORD=2|OwnerIndex=1015|OwnerPartId=1|FormalType=1|PinConglomerate=58|PinLength=30|Location.X=1200|Location.Y=908|Name=17|Designator=A-17|PinPropagationDelay=0.000000E+000
|RECORD=2|OwnerIndex=1015|OwnerPartId=1|FormalType=1|PinConglomerate=56|PinLength=30|Location.X=1260|Location.Y=908|Name=18|Designator=A-18|PinPropagationDelay=0.000000E+000
|RECORD=2|OwnerIndex=1015|OwnerPartId=1|FormalType=1|PinConglomerate=58|PinLength=30|Location.X=1200|Location.Y=898|Name=19|Designator=A-19|PinPropagationDelay=0.000000E+000
|RECORD=2|OwnerIndex=1015|OwnerPartId=1|FormalType=1|PinConglomerate=56|PinLength=30|Location.X=1260|Location.Y=898|Name=20|Designator=A-20|PinPropagationDelay=0.000000E+000
|RECORD=2|OwnerIndex=1015|OwnerPartId=1|FormalType=1|PinConglomerate=58|PinLength=30|Location.X=1200|Location.Y=888|Name=21|Designator=A-21|PinPropagationDelay=0.000000E+000
|RECORD=2|OwnerIndex=1015|OwnerPartId=1|FormalType=1|PinConglomerate=56|PinLength=30|Location.X=1260|Location.Y=888|Name=22|Designator=A-22|PinPropagationDelay=0.000000E+000
|RECORD=2|OwnerIndex=1015|OwnerPartId=1|FormalType=1|PinConglomerate=58|PinLength=30|Location.X=1200|Location.Y=878|Name=23|Designator=A-23|PinPropagationDelay=0.000000E+000
|RECORD=2|OwnerIndex=1015|OwnerPartId=1|FormalType=1|PinConglomerate=56|PinLength=30|Location.X=1260|Location.Y=878|Name=24|Designator=A-24|PinPropagationDelay=0.000000E+000
|RECORD=2|OwnerIndex=1015|OwnerPartId=1|FormalType=1|PinConglomerate=58|PinLength=30|Location.X=1200|Location.Y=868|Name=25|Designator=A-25|PinPropagationDelay=0.000000E+000
|RECORD=2|OwnerIndex=1015|OwnerPartId=1|FormalType=1|PinConglomerate=56|PinLength=30|Location.X=1260|Location.Y=868|Name=26|Designator=A-26|PinPropagationDelay=0.000000E+000
|RECORD=2|OwnerIndex=1015|OwnerPartId=1|FormalType=1|PinConglomerate=58|PinLength=30|Location.X=1200|Location.Y=858|Name=27|Designator=A-27|PinPropagationDelay=0.000000E+000
|RECORD=2|OwnerIndex=1015|OwnerPartId=1|FormalType=1|PinConglomerate=56|PinLength=30|Location.X=1260|Location.Y=858|Name=28|Designator=A-28|PinPropagationDelay=0.000000E+000
|RECORD=2|OwnerIndex=1015|OwnerPartId=1|FormalType=1|PinConglomerate=58|PinLength=30|Location.X=1200|Location.Y=848|Name=29|Designator=A-29|PinPropagationDelay=0.000000E+000
|RECORD=2|OwnerIndex=1015|OwnerPartId=1|FormalType=1|PinConglomerate=56|PinLength=30|Location.X=1260|Location.Y=848|Name=30|Designator=A-30|PinPropagationDelay=0.000000E+000
|RECORD=2|OwnerIndex=1015|OwnerPartId=1|FormalType=1|PinConglomerate=58|PinLength=30|Location.X=1200|Location.Y=838|Name=31|Designator=A-31|PinPropagationDelay=0.000000E+000
|RECORD=2|OwnerIndex=1015|OwnerPartId=1|FormalType=1|PinConglomerate=56|PinLength=30|Location.X=1260|Location.Y=838|Name=32|Designator=A-32|PinPropagationDelay=0.000000E+000
|RECORD=2|OwnerIndex=1015|OwnerPartId=1|FormalType=1|PinConglomerate=58|PinLength=30|Location.X=1200|Location.Y=828|Name=33|Designator=A-33|PinPropagationDelay=0.000000E+000
|RECORD=2|OwnerIndex=1015|OwnerPartId=1|FormalType=1|PinConglomerate=56|PinLength=30|Location.X=1260|Location.Y=828|Name=34|Designator=A-34|PinPropagationDelay=0.000000E+000
|RECORD=2|OwnerIndex=1015|OwnerPartId=1|FormalType=1|PinConglomerate=58|PinLength=30|Location.X=1200|Location.Y=818|Name=35|Designator=A-35|PinPropagationDelay=0.000000E+000
|RECORD=2|OwnerIndex=1015|OwnerPartId=1|FormalType=1|PinConglomerate=56|PinLength=30|Location.X=1260|Location.Y=818|Name=36|Designator=A-36|PinPropagationDelay=0.000000E+000
|RECORD=2|OwnerIndex=1015|OwnerPartId=1|FormalType=1|PinConglomerate=58|PinLength=30|Location.X=1200|Location.Y=808|Name=37|Designator=A-37|PinPropagationDelay=0.000000E+000
|RECORD=2|OwnerIndex=1015|OwnerPartId=1|FormalType=1|PinConglomerate=56|PinLength=30|Location.X=1260|Location.Y=808|Name=38|Designator=A-38|PinPropagationDelay=0.000000E+000
|RECORD=2|OwnerIndex=1015|OwnerPartId=1|FormalType=1|PinConglomerate=58|PinLength=30|Location.X=1200|Location.Y=798|Name=39|Designator=A-39|PinPropagationDelay=0.000000E+000
|RECORD=2|OwnerIndex=1015|OwnerPartId=1|FormalType=1|PinConglomerate=56|PinLength=30|Location.X=1260|Location.Y=798|Name=40|Designator=A-40|PinPropagationDelay=0.000000E+000
|RECORD=2|OwnerIndex=1015|OwnerPartId=1|FormalType=1|PinConglomerate=58|PinLength=30|Location.X=1200|Location.Y=788|Name=41|Designator=A-41|PinPropagationDelay=0.000000E+000
|RECORD=2|OwnerIndex=1015|OwnerPartId=1|FormalType=1|PinConglomerate=56|PinLength=30|Location.X=1260|Location.Y=788|Name=42|Designator=A-42|PinPropagationDelay=0.000000E+000
|RECORD=2|OwnerIndex=1015|OwnerPartId=1|FormalType=1|PinConglomerate=58|PinLength=30|Location.X=1200|Location.Y=778|Name=43|Designator=A-43|PinPropagationDelay=0.000000E+000
|RECORD=2|OwnerIndex=1015|OwnerPartId=1|FormalType=1|PinConglomerate=56|PinLength=30|Location.X=1260|Location.Y=778|Name=44|Designator=A-44|PinPropagationDelay=0.000000E+000
|RECORD=2|OwnerIndex=1015|OwnerPartId=1|FormalType=1|PinConglomerate=58|PinLength=30|Location.X=1200|Location.Y=768|Name=45|Designator=A-45|PinPropagationDelay=0.000000E+000
|RECORD=2|OwnerIndex=1015|OwnerPartId=1|FormalType=1|PinConglomerate=56|PinLength=30|Location.X=1260|Location.Y=768|Name=46|Designator=A-46|PinPropagationDelay=0.000000E+000
|RECORD=2|OwnerIndex=1015|OwnerPartId=1|FormalType=1|PinConglomerate=58|PinLength=30|Location.X=1200|Location.Y=758|Name=47|Designator=A-47|PinPropagationDelay=0.000000E+000
|RECORD=2|OwnerIndex=1015|OwnerPartId=1|FormalType=1|PinConglomerate=56|PinLength=30|Location.X=1260|Location.Y=758|Name=48|Designator=A-48|PinPropagationDelay=0.000000E+000
|RECORD=2|OwnerIndex=1015|OwnerPartId=1|FormalType=1|PinConglomerate=58|PinLength=30|Location.X=1200|Location.Y=748|Name=49|Designator=A-49|PinPropagationDelay=0.000000E+000
|RECORD=2|OwnerIndex=1015|OwnerPartId=1|FormalType=1|PinConglomerate=56|PinLength=30|Location.X=1260|Location.Y=748|Name=50|Designator=A-50|PinPropagationDelay=0.000000E+000
|RECORD=2|OwnerIndex=1015|OwnerPartId=1|FormalType=1|PinConglomerate=58|PinLength=30|Location.X=1200|Location.Y=738|Name=51|Designator=A-51|PinPropagationDelay=0.000000E+000
|RECORD=2|OwnerIndex=1015|OwnerPartId=1|FormalType=1|PinConglomerate=56|PinLength=30|Location.X=1260|Location.Y=738|Name=52|Designator=A-52|PinPropagationDelay=0.000000E+000
|RECORD=2|OwnerIndex=1015|OwnerPartId=1|FormalType=1|PinConglomerate=58|PinLength=30|Location.X=1200|Location.Y=728|Name=53|Designator=A-53|PinPropagationDelay=0.000000E+000
|RECORD=2|OwnerIndex=1015|OwnerPartId=1|FormalType=1|PinConglomerate=56|PinLength=30|Location.X=1260|Location.Y=728|Name=54|Designator=A-54|PinPropagationDelay=0.000000E+000
|RECORD=2|OwnerIndex=1015|OwnerPartId=1|FormalType=1|PinConglomerate=58|PinLength=30|Location.X=1200|Location.Y=718|Name=55|Designator=A-55|PinPropagationDelay=0.000000E+000
|RECORD=2|OwnerIndex=1015|OwnerPartId=1|FormalType=1|PinConglomerate=56|PinLength=30|Location.X=1260|Location.Y=718|Name=56|Designator=A-56|PinPropagationDelay=0.000000E+000
|RECORD=2|OwnerIndex=1015|OwnerPartId=1|FormalType=1|PinConglomerate=58|PinLength=30|Location.X=1200|Location.Y=708|Name=57|Designator=A-57|PinPropagationDelay=0.000000E+000
|RECORD=2|OwnerIndex=1015|OwnerPartId=1|FormalType=1|PinConglomerate=56|PinLength=30|Location.X=1260|Location.Y=708|Name=58|Designator=A-58|PinPropagationDelay=0.000000E+000
|RECORD=2|OwnerIndex=1015|OwnerPartId=1|FormalType=1|PinConglomerate=58|PinLength=30|Location.X=1200|Location.Y=698|Name=59|Designator=A-59|PinPropagationDelay=0.000000E+000
|RECORD=2|OwnerIndex=1015|OwnerPartId=1|FormalType=1|PinConglomerate=56|PinLength=30|Location.X=1260|Location.Y=698|Name=60|Designator=A-60|PinPropagationDelay=0.000000E+000
|RECORD=2|OwnerIndex=1015|OwnerPartId=1|FormalType=1|PinConglomerate=58|PinLength=30|Location.X=1200|Location.Y=688|Name=61|Designator=A-61|PinPropagationDelay=0.000000E+000
|RECORD=2|OwnerIndex=1015|OwnerPartId=1|FormalType=1|PinConglomerate=56|PinLength=30|Location.X=1260|Location.Y=688|Name=62|Designator=A-62|PinPropagationDelay=0.000000E+000
|RECORD=2|OwnerIndex=1015|OwnerPartId=1|FormalType=1|PinConglomerate=58|PinLength=30|Location.X=1200|Location.Y=678|Name=63|Designator=A-63|PinPropagationDelay=0.000000E+000
|RECORD=2|OwnerIndex=1015|OwnerPartId=1|FormalType=1|PinConglomerate=56|PinLength=30|Location.X=1260|Location.Y=678|Name=64|Designator=A-64|PinPropagationDelay=0.000000E+000
|RECORD=2|OwnerIndex=1015|OwnerPartId=1|FormalType=1|PinConglomerate=58|PinLength=30|Location.X=1200|Location.Y=668|Name=65|Designator=A-65|PinPropagationDelay=0.000000E+000
|RECORD=2|OwnerIndex=1015|OwnerPartId=1|FormalType=1|PinConglomerate=56|PinLength=30|Location.X=1260|Location.Y=668|Name=66|Designator=A-66|PinPropagationDelay=0.000000E+000
|RECORD=2|OwnerIndex=1015|OwnerPartId=1|FormalType=1|PinConglomerate=58|PinLength=30|Location.X=1200|Location.Y=658|Name=67|Designator=A-67|PinPropagationDelay=0.000000E+000
|RECORD=2|OwnerIndex=1015|OwnerPartId=1|FormalType=1|PinConglomerate=56|PinLength=30|Location.X=1260|Location.Y=658|Name=68|Designator=A-68|PinPropagationDelay=0.000000E+000
|RECORD=2|OwnerIndex=1015|OwnerPartId=1|FormalType=1|PinConglomerate=58|PinLength=30|Location.X=1200|Location.Y=648|Name=69|Designator=A-69|PinPropagationDelay=0.000000E+000
|RECORD=2|OwnerIndex=1015|OwnerPartId=1|FormalType=1|PinConglomerate=56|PinLength=30|Location.X=1260|Location.Y=648|Name=70|Designator=A-70|PinPropagationDelay=0.000000E+000
|RECORD=2|OwnerIndex=1015|OwnerPartId=1|FormalType=1|PinConglomerate=58|PinLength=30|Location.X=1200|Location.Y=638|Name=71|Designator=A-71|PinPropagationDelay=0.000000E+000
|RECORD=2|OwnerIndex=1015|OwnerPartId=1|FormalType=1|PinConglomerate=56|PinLength=30|Location.X=1260|Location.Y=638|Name=72|Designator=A-72|PinPropagationDelay=0.000000E+000
|RECORD=2|OwnerIndex=1015|OwnerPartId=1|FormalType=1|PinConglomerate=58|PinLength=30|Location.X=1200|Location.Y=628|Name=73|Designator=A-73|PinPropagationDelay=0.000000E+000
|RECORD=2|OwnerIndex=1015|OwnerPartId=1|FormalType=1|PinConglomerate=56|PinLength=30|Location.X=1260|Location.Y=628|Name=74|Designator=A-74|PinPropagationDelay=0.000000E+000
|RECORD=2|OwnerIndex=1015|OwnerPartId=1|FormalType=1|PinConglomerate=58|PinLength=30|Location.X=1200|Location.Y=618|Name=75|Designator=A-75|PinPropagationDelay=0.000000E+000
|RECORD=2|OwnerIndex=1015|OwnerPartId=1|FormalType=1|PinConglomerate=56|PinLength=30|Location.X=1260|Location.Y=618|Name=76|Designator=A-76|PinPropagationDelay=0.000000E+000
|RECORD=2|OwnerIndex=1015|OwnerPartId=1|FormalType=1|PinConglomerate=58|PinLength=30|Location.X=1200|Location.Y=608|Name=77|Designator=A-77|PinPropagationDelay=0.000000E+000
|RECORD=2|OwnerIndex=1015|OwnerPartId=1|FormalType=1|PinConglomerate=56|PinLength=30|Location.X=1260|Location.Y=608|Name=78|Designator=A-78|PinPropagationDelay=0.000000E+000
|RECORD=2|OwnerIndex=1015|OwnerPartId=1|FormalType=1|PinConglomerate=58|PinLength=30|Location.X=1200|Location.Y=598|Name=79|Designator=A-79|PinPropagationDelay=0.000000E+000
|RECORD=2|OwnerIndex=1015|OwnerPartId=1|FormalType=1|PinConglomerate=56|PinLength=30|Location.X=1260|Location.Y=598|Name=80|Designator=A-80|PinPropagationDelay=0.000000E+000
|RECORD=2|OwnerIndex=1015|OwnerPartId=1|FormalType=1|PinConglomerate=58|PinLength=30|Location.X=1200|Location.Y=588|Name=81|Designator=A-81|PinPropagationDelay=0.000000E+000
|RECORD=2|OwnerIndex=1015|OwnerPartId=1|FormalType=1|PinConglomerate=56|PinLength=30|Location.X=1260|Location.Y=588|Name=82|Designator=A-82|PinPropagationDelay=0.000000E+000
|RECORD=2|OwnerIndex=1015|OwnerPartId=1|FormalType=1|PinConglomerate=58|PinLength=30|Location.X=1200|Location.Y=578|Name=83|Designator=A-83|PinPropagationDelay=0.000000E+000
|RECORD=2|OwnerIndex=1015|OwnerPartId=1|FormalType=1|PinConglomerate=56|PinLength=30|Location.X=1260|Location.Y=578|Name=84|Designator=A-84|PinPropagationDelay=0.000000E+000
|RECORD=34|OwnerIndex=1015|IndexInSheet=-1|OwnerPartId=-1|Location.X=1200|Location.Y=998|Color=8388608|FontID=1|Text=P1|Name=Designator|ReadOnlyState=1
|RECORD=41|OwnerIndex=1015|IndexInSheet=-1|OwnerPartId=-1|Location.X=1200|Location.Y=558|Color=8388608|FontID=1|Text=FPGA_CONN|Name=Comment
|RECORD=44|OwnerIndex=1015
|RECORD=45|OwnerIndex=1694|IndexInSheet=-1|ModelName=FPGA_CONN|ModelType=PCBLIB|DatafileCount=1|ModelDatafileEntity0=FPGA_CONN|ModelDatafileKind0=PCBLib|IsCurrent=T
|RECORD=46|OwnerIndex=1695
|RECORD=48|OwnerIndex=1695
|RECORD=1|LibReference=FPGA_CONN|PartCount=5|DisplayModeCount=1|IndexInSheet=305|OwnerPartId=-1|Location.X=460|Location.Y=498|CurrentPartId=3|LibraryPath=*|SourceLibraryName=FPGA_CONN.SchLib|TargetFileName=*|AreaColor=11599871|Color=128|PartIDLocked=T|NotUseDBTableName=T|DesignItemId=FPGA_CONN|AllPinCount=336
|RECORD=14|OwnerIndex=1698|IsNotAccesible=T|OwnerPartId=2|Location.X=490|Location.Y=78|Corner.X=550|Corner.Y=508|Color=128|AreaColor=11599871|IsSolid=T
|RECORD=2|OwnerIndex=1698|OwnerPartId=2|FormalType=1|PinConglomerate=58|PinLength=30|Location.X=490|Location.Y=498|Name=1|Designator=B-1|PinPropagationDelay=0.000000E+000
|RECORD=2|OwnerIndex=1698|OwnerPartId=2|FormalType=1|PinConglomerate=56|PinLength=30|Location.X=550|Location.Y=498|Name=2|Designator=B-2|PinPropagationDelay=0.000000E+000
|RECORD=2|OwnerIndex=1698|OwnerPartId=2|FormalType=1|PinConglomerate=58|PinLength=30|Location.X=490|Location.Y=488|Name=3|Designator=B-3|PinPropagationDelay=0.000000E+000
|RECORD=2|OwnerIndex=1698|OwnerPartId=2|FormalType=1|PinConglomerate=56|PinLength=30|Location.X=550|Location.Y=488|Name=4|Designator=B-4|PinPropagationDelay=0.000000E+000
|RECORD=2|OwnerIndex=1698|OwnerPartId=2|FormalType=1|PinConglomerate=58|PinLength=30|Location.X=490|Location.Y=478|Name=5|Designator=B-5|PinPropagationDelay=0.000000E+000
|RECORD=2|OwnerIndex=1698|OwnerPartId=2|FormalType=1|PinConglomerate=56|PinLength=30|Location.X=550|Location.Y=478|Name=6|Designator=B-6|PinPropagationDelay=0.000000E+000
|RECORD=2|OwnerIndex=1698|OwnerPartId=2|FormalType=1|PinConglomerate=58|PinLength=30|Location.X=490|Location.Y=468|Name=7|Designator=B-7|PinPropagationDelay=0.000000E+000
|RECORD=2|OwnerIndex=1698|OwnerPartId=2|FormalType=1|PinConglomerate=56|PinLength=30|Location.X=550|Location.Y=468|Name=8|Designator=B-8|PinPropagationDelay=0.000000E+000
|RECORD=2|OwnerIndex=1698|OwnerPartId=2|FormalType=1|PinConglomerate=58|PinLength=30|Location.X=490|Location.Y=458|Name=9|Designator=B-9|PinPropagationDelay=0.000000E+000
|RECORD=2|OwnerIndex=1698|OwnerPartId=2|FormalType=1|PinConglomerate=56|PinLength=30|Location.X=550|Location.Y=458|Name=10|Designator=B-10|PinPropagationDelay=0.000000E+000
|RECORD=2|OwnerIndex=1698|OwnerPartId=2|FormalType=1|PinConglomerate=58|PinLength=30|Location.X=490|Location.Y=448|Name=11|Designator=B-11|PinPropagationDelay=0.000000E+000
|RECORD=2|OwnerIndex=1698|OwnerPartId=2|FormalType=1|PinConglomerate=56|PinLength=30|Location.X=550|Location.Y=448|Name=12|Designator=B-12|PinPropagationDelay=0.000000E+000
|RECORD=2|OwnerIndex=1698|OwnerPartId=2|FormalType=1|PinConglomerate=58|PinLength=30|Location.X=490|Location.Y=438|Name=13|Designator=B-13|PinPropagationDelay=0.000000E+000
|RECORD=2|OwnerIndex=1698|OwnerPartId=2|FormalType=1|PinConglomerate=56|PinLength=30|Location.X=550|Location.Y=438|Name=14|Designator=B-14|PinPropagationDelay=0.000000E+000
|RECORD=2|OwnerIndex=1698|OwnerPartId=2|FormalType=1|PinConglomerate=58|PinLength=30|Location.X=490|Location.Y=428|Name=15|Designator=B-15|PinPropagationDelay=0.000000E+000
|RECORD=2|OwnerIndex=1698|OwnerPartId=2|FormalType=1|PinConglomerate=56|PinLength=30|Location.X=550|Location.Y=428|Name=16|Designator=B-16|PinPropagationDelay=0.000000E+000
|RECORD=2|OwnerIndex=1698|OwnerPartId=2|FormalType=1|PinConglomerate=58|PinLength=30|Location.X=490|Location.Y=418|Name=17|Designator=B-17|PinPropagationDelay=0.000000E+000
|RECORD=2|OwnerIndex=1698|OwnerPartId=2|FormalType=1|PinConglomerate=56|PinLength=30|Location.X=550|Location.Y=418|Name=18|Designator=B-18|PinPropagationDelay=0.000000E+000
|RECORD=2|OwnerIndex=1698|OwnerPartId=2|FormalType=1|PinConglomerate=58|PinLength=30|Location.X=490|Location.Y=408|Name=19|Designator=B-19|PinPropagationDelay=0.000000E+000
|RECORD=2|OwnerIndex=1698|OwnerPartId=2|FormalType=1|PinConglomerate=56|PinLength=30|Location.X=550|Location.Y=408|Name=20|Designator=B-20|PinPropagationDelay=0.000000E+000
|RECORD=2|OwnerIndex=1698|OwnerPartId=2|FormalType=1|PinConglomerate=58|PinLength=30|Location.X=490|Location.Y=398|Name=21|Designator=B-21|PinPropagationDelay=0.000000E+000
|RECORD=2|OwnerIndex=1698|OwnerPartId=2|FormalType=1|PinConglomerate=56|PinLength=30|Location.X=550|Location.Y=398|Name=22|Designator=B-22|PinPropagationDelay=0.000000E+000
|RECORD=2|OwnerIndex=1698|OwnerPartId=2|FormalType=1|PinConglomerate=58|PinLength=30|Location.X=490|Location.Y=388|Name=23|Designator=B-23|PinPropagationDelay=0.000000E+000
|RECORD=2|OwnerIndex=1698|OwnerPartId=2|FormalType=1|PinConglomerate=56|PinLength=30|Location.X=550|Location.Y=388|Name=24|Designator=B-24|PinPropagationDelay=0.000000E+000
|RECORD=2|OwnerIndex=1698|OwnerPartId=2|FormalType=1|PinConglomerate=58|PinLength=30|Location.X=490|Location.Y=378|Name=25|Designator=B-25|PinPropagationDelay=0.000000E+000
|RECORD=2|OwnerIndex=1698|OwnerPartId=2|FormalType=1|PinConglomerate=56|PinLength=30|Location.X=550|Location.Y=378|Name=26|Designator=B-26|PinPropagationDelay=0.000000E+000
|RECORD=2|OwnerIndex=1698|OwnerPartId=2|FormalType=1|PinConglomerate=58|PinLength=30|Location.X=490|Location.Y=368|Name=27|Designator=B-27|PinPropagationDelay=0.000000E+000
|RECORD=2|OwnerIndex=1698|OwnerPartId=2|FormalType=1|PinConglomerate=56|PinLength=30|Location.X=550|Location.Y=368|Name=28|Designator=B-28|PinPropagationDelay=0.000000E+000
|RECORD=2|OwnerIndex=1698|OwnerPartId=2|FormalType=1|PinConglomerate=58|PinLength=30|Location.X=490|Location.Y=358|Name=29|Designator=B-29|PinPropagationDelay=0.000000E+000
|RECORD=2|OwnerIndex=1698|OwnerPartId=2|FormalType=1|PinConglomerate=56|PinLength=30|Location.X=550|Location.Y=358|Name=30|Designator=B-30|PinPropagationDelay=0.000000E+000
|RECORD=2|OwnerIndex=1698|OwnerPartId=2|FormalType=1|PinConglomerate=58|PinLength=30|Location.X=490|Location.Y=348|Name=31|Designator=B-31|PinPropagationDelay=0.000000E+000
|RECORD=2|OwnerIndex=1698|OwnerPartId=2|FormalType=1|PinConglomerate=56|PinLength=30|Location.X=550|Location.Y=348|Name=32|Designator=B-32|PinPropagationDelay=0.000000E+000
|RECORD=2|OwnerIndex=1698|OwnerPartId=2|FormalType=1|PinConglomerate=58|PinLength=30|Location.X=490|Location.Y=338|Name=33|Designator=B-33|PinPropagationDelay=0.000000E+000
|RECORD=2|OwnerIndex=1698|OwnerPartId=2|FormalType=1|PinConglomerate=56|PinLength=30|Location.X=550|Location.Y=338|Name=34|Designator=B-34|PinPropagationDelay=0.000000E+000
|RECORD=2|OwnerIndex=1698|OwnerPartId=2|FormalType=1|PinConglomerate=58|PinLength=30|Location.X=490|Location.Y=328|Name=35|Designator=B-35|PinPropagationDelay=0.000000E+000
|RECORD=2|OwnerIndex=1698|OwnerPartId=2|FormalType=1|PinConglomerate=56|PinLength=30|Location.X=550|Location.Y=328|Name=36|Designator=B-36|PinPropagationDelay=0.000000E+000
|RECORD=2|OwnerIndex=1698|OwnerPartId=2|FormalType=1|PinConglomerate=58|PinLength=30|Location.X=490|Location.Y=318|Name=37|Designator=B-37|PinPropagationDelay=0.000000E+000
|RECORD=2|OwnerIndex=1698|OwnerPartId=2|FormalType=1|PinConglomerate=56|PinLength=30|Location.X=550|Location.Y=318|Name=38|Designator=B-38|PinPropagationDelay=0.000000E+000
|RECORD=2|OwnerIndex=1698|OwnerPartId=2|FormalType=1|PinConglomerate=58|PinLength=30|Location.X=490|Location.Y=308|Name=39|Designator=B-39|PinPropagationDelay=0.000000E+000
|RECORD=2|OwnerIndex=1698|OwnerPartId=2|FormalType=1|PinConglomerate=56|PinLength=30|Location.X=550|Location.Y=308|Name=40|Designator=B-40|PinPropagationDelay=0.000000E+000
|RECORD=2|OwnerIndex=1698|OwnerPartId=2|FormalType=1|PinConglomerate=58|PinLength=30|Location.X=490|Location.Y=298|Name=41|Designator=B-41|PinPropagationDelay=0.000000E+000
|RECORD=2|OwnerIndex=1698|OwnerPartId=2|FormalType=1|PinConglomerate=56|PinLength=30|Location.X=550|Location.Y=298|Name=42|Designator=B-42|PinPropagationDelay=0.000000E+000
|RECORD=2|OwnerIndex=1698|OwnerPartId=2|FormalType=1|PinConglomerate=58|PinLength=30|Location.X=490|Location.Y=288|Name=43|Designator=B-43|PinPropagationDelay=0.000000E+000
|RECORD=2|OwnerIndex=1698|OwnerPartId=2|FormalType=1|PinConglomerate=56|PinLength=30|Location.X=550|Location.Y=288|Name=44|Designator=B-44|PinPropagationDelay=0.000000E+000
|RECORD=2|OwnerIndex=1698|OwnerPartId=2|FormalType=1|PinConglomerate=58|PinLength=30|Location.X=490|Location.Y=278|Name=45|Designator=B-45|PinPropagationDelay=0.000000E+000
|RECORD=2|OwnerIndex=1698|OwnerPartId=2|FormalType=1|PinConglomerate=56|PinLength=30|Location.X=550|Location.Y=278|Name=46|Designator=B-46|PinPropagationDelay=0.000000E+000
|RECORD=2|OwnerIndex=1698|OwnerPartId=2|FormalType=1|PinConglomerate=58|PinLength=30|Location.X=490|Location.Y=268|Name=47|Designator=B-47|PinPropagationDelay=0.000000E+000
|RECORD=2|OwnerIndex=1698|OwnerPartId=2|FormalType=1|PinConglomerate=56|PinLength=30|Location.X=550|Location.Y=268|Name=48|Designator=B-48|PinPropagationDelay=0.000000E+000
|RECORD=2|OwnerIndex=1698|OwnerPartId=2|FormalType=1|PinConglomerate=58|PinLength=30|Location.X=490|Location.Y=258|Name=49|Designator=B-49|PinPropagationDelay=0.000000E+000
|RECORD=2|OwnerIndex=1698|OwnerPartId=2|FormalType=1|PinConglomerate=56|PinLength=30|Location.X=550|Location.Y=258|Name=50|Designator=B-50|PinPropagationDelay=0.000000E+000
|RECORD=2|OwnerIndex=1698|OwnerPartId=2|FormalType=1|PinConglomerate=58|PinLength=30|Location.X=490|Location.Y=248|Name=51|Designator=B-51|PinPropagationDelay=0.000000E+000
|RECORD=2|OwnerIndex=1698|OwnerPartId=2|FormalType=1|PinConglomerate=56|PinLength=30|Location.X=550|Location.Y=248|Name=52|Designator=B-52|PinPropagationDelay=0.000000E+000
|RECORD=2|OwnerIndex=1698|OwnerPartId=2|FormalType=1|PinConglomerate=58|PinLength=30|Location.X=490|Location.Y=238|Name=53|Designator=B-53|PinPropagationDelay=0.000000E+000
|RECORD=2|OwnerIndex=1698|OwnerPartId=2|FormalType=1|PinConglomerate=56|PinLength=30|Location.X=550|Location.Y=238|Name=54|Designator=B-54|PinPropagationDelay=0.000000E+000
|RECORD=2|OwnerIndex=1698|OwnerPartId=2|FormalType=1|PinConglomerate=58|PinLength=30|Location.X=490|Location.Y=228|Name=55|Designator=B-55|PinPropagationDelay=0.000000E+000
|RECORD=2|OwnerIndex=1698|OwnerPartId=2|FormalType=1|PinConglomerate=56|PinLength=30|Location.X=550|Location.Y=228|Name=56|Designator=B-56|PinPropagationDelay=0.000000E+000
|RECORD=2|OwnerIndex=1698|OwnerPartId=2|FormalType=1|PinConglomerate=58|PinLength=30|Location.X=490|Location.Y=218|Name=57|Designator=B-57|PinPropagationDelay=0.000000E+000
|RECORD=2|OwnerIndex=1698|OwnerPartId=2|FormalType=1|PinConglomerate=56|PinLength=30|Location.X=550|Location.Y=218|Name=58|Designator=B-58|PinPropagationDelay=0.000000E+000
|RECORD=2|OwnerIndex=1698|OwnerPartId=2|FormalType=1|PinConglomerate=58|PinLength=30|Location.X=490|Location.Y=208|Name=59|Designator=B-59|PinPropagationDelay=0.000000E+000
|RECORD=2|OwnerIndex=1698|OwnerPartId=2|FormalType=1|PinConglomerate=56|PinLength=30|Location.X=550|Location.Y=208|Name=60|Designator=B-60|PinPropagationDelay=0.000000E+000
|RECORD=2|OwnerIndex=1698|OwnerPartId=2|FormalType=1|PinConglomerate=58|PinLength=30|Location.X=490|Location.Y=198|Name=61|Designator=B-61|PinPropagationDelay=0.000000E+000
|RECORD=2|OwnerIndex=1698|OwnerPartId=2|FormalType=1|PinConglomerate=56|PinLength=30|Location.X=550|Location.Y=198|Name=62|Designator=B-62|PinPropagationDelay=0.000000E+000
|RECORD=2|OwnerIndex=1698|OwnerPartId=2|FormalType=1|PinConglomerate=58|PinLength=30|Location.X=490|Location.Y=188|Name=63|Designator=B-63|PinPropagationDelay=0.000000E+000
|RECORD=2|OwnerIndex=1698|OwnerPartId=2|FormalType=1|PinConglomerate=56|PinLength=30|Location.X=550|Location.Y=188|Name=64|Designator=B-64|PinPropagationDelay=0.000000E+000
|RECORD=2|OwnerIndex=1698|OwnerPartId=2|FormalType=1|PinConglomerate=58|PinLength=30|Location.X=490|Location.Y=178|Name=65|Designator=B-65|PinPropagationDelay=0.000000E+000
|RECORD=2|OwnerIndex=1698|OwnerPartId=2|FormalType=1|PinConglomerate=56|PinLength=30|Location.X=550|Location.Y=178|Name=66|Designator=B-66|PinPropagationDelay=0.000000E+000
|RECORD=2|OwnerIndex=1698|OwnerPartId=2|FormalType=1|PinConglomerate=58|PinLength=30|Location.X=490|Location.Y=168|Name=67|Designator=B-67|PinPropagationDelay=0.000000E+000
|RECORD=2|OwnerIndex=1698|OwnerPartId=2|FormalType=1|PinConglomerate=56|PinLength=30|Location.X=550|Location.Y=168|Name=68|Designator=B-68|PinPropagationDelay=0.000000E+000
|RECORD=2|OwnerIndex=1698|OwnerPartId=2|FormalType=1|PinConglomerate=58|PinLength=30|Location.X=490|Location.Y=158|Name=69|Designator=B-69|PinPropagationDelay=0.000000E+000
|RECORD=2|OwnerIndex=1698|OwnerPartId=2|FormalType=1|PinConglomerate=56|PinLength=30|Location.X=550|Location.Y=158|Name=70|Designator=B-70|PinPropagationDelay=0.000000E+000
|RECORD=2|OwnerIndex=1698|OwnerPartId=2|FormalType=1|PinConglomerate=58|PinLength=30|Location.X=490|Location.Y=148|Name=71|Designator=B-71|PinPropagationDelay=0.000000E+000
|RECORD=2|OwnerIndex=1698|OwnerPartId=2|FormalType=1|PinConglomerate=56|PinLength=30|Location.X=550|Location.Y=148|Name=72|Designator=B-72|PinPropagationDelay=0.000000E+000
|RECORD=2|OwnerIndex=1698|OwnerPartId=2|FormalType=1|PinConglomerate=58|PinLength=30|Location.X=490|Location.Y=138|Name=73|Designator=B-73|PinPropagationDelay=0.000000E+000
|RECORD=2|OwnerIndex=1698|OwnerPartId=2|FormalType=1|PinConglomerate=56|PinLength=30|Location.X=550|Location.Y=138|Name=74|Designator=B-74|PinPropagationDelay=0.000000E+000
|RECORD=2|OwnerIndex=1698|OwnerPartId=2|FormalType=1|PinConglomerate=58|PinLength=30|Location.X=490|Location.Y=128|Name=75|Designator=B-75|PinPropagationDelay=0.000000E+000
|RECORD=2|OwnerIndex=1698|OwnerPartId=2|FormalType=1|PinConglomerate=56|PinLength=30|Location.X=550|Location.Y=128|Name=76|Designator=B-76|PinPropagationDelay=0.000000E+000
|RECORD=2|OwnerIndex=1698|OwnerPartId=2|FormalType=1|PinConglomerate=58|PinLength=30|Location.X=490|Location.Y=118|Name=77|Designator=B-77|PinPropagationDelay=0.000000E+000
|RECORD=2|OwnerIndex=1698|OwnerPartId=2|FormalType=1|PinConglomerate=56|PinLength=30|Location.X=550|Location.Y=118|Name=78|Designator=B-78|PinPropagationDelay=0.000000E+000
|RECORD=2|OwnerIndex=1698|OwnerPartId=2|FormalType=1|PinConglomerate=58|PinLength=30|Location.X=490|Location.Y=108|Name=79|Designator=B-79|PinPropagationDelay=0.000000E+000
|RECORD=2|OwnerIndex=1698|OwnerPartId=2|FormalType=1|PinConglomerate=56|PinLength=30|Location.X=550|Location.Y=108|Name=80|Designator=B-80|PinPropagationDelay=0.000000E+000
|RECORD=2|OwnerIndex=1698|OwnerPartId=2|FormalType=1|PinConglomerate=58|PinLength=30|Location.X=490|Location.Y=98|Name=81|Designator=B-81|PinPropagationDelay=0.000000E+000
|RECORD=2|OwnerIndex=1698|OwnerPartId=2|FormalType=1|PinConglomerate=56|PinLength=30|Location.X=550|Location.Y=98|Name=82|Designator=B-82|PinPropagationDelay=0.000000E+000
|RECORD=2|OwnerIndex=1698|OwnerPartId=2|FormalType=1|PinConglomerate=58|PinLength=30|Location.X=490|Location.Y=88|Name=83|Designator=B-83|PinPropagationDelay=0.000000E+000
|RECORD=2|OwnerIndex=1698|OwnerPartId=2|FormalType=1|PinConglomerate=56|PinLength=30|Location.X=550|Location.Y=88|Name=84|Designator=B-84|PinPropagationDelay=0.000000E+000
|RECORD=14|OwnerIndex=1698|IsNotAccesible=T|IndexInSheet=85|OwnerPartId=3|Location.X=490|Location.Y=78|Corner.X=550|Corner.Y=508|Color=128|AreaColor=11599871|IsSolid=T
|RECORD=2|OwnerIndex=1698|OwnerPartId=3|FormalType=1|PinConglomerate=58|PinLength=30|Location.X=490|Location.Y=498|Name=1|Designator=C-1|PinPropagationDelay=0.000000E+000
|RECORD=2|OwnerIndex=1698|OwnerPartId=3|FormalType=1|PinConglomerate=56|PinLength=30|Location.X=550|Location.Y=498|Name=2|Designator=C-2|PinPropagationDelay=0.000000E+000
|RECORD=2|OwnerIndex=1698|OwnerPartId=3|FormalType=1|PinConglomerate=58|PinLength=30|Location.X=490|Location.Y=488|Name=3|Designator=C-3|PinPropagationDelay=0.000000E+000
|RECORD=2|OwnerIndex=1698|OwnerPartId=3|FormalType=1|PinConglomerate=56|PinLength=30|Location.X=550|Location.Y=488|Name=4|Designator=C-4|PinPropagationDelay=0.000000E+000
|RECORD=2|OwnerIndex=1698|OwnerPartId=3|FormalType=1|PinConglomerate=58|PinLength=30|Location.X=490|Location.Y=478|Name=5|Designator=C-5|PinPropagationDelay=0.000000E+000
|RECORD=2|OwnerIndex=1698|OwnerPartId=3|FormalType=1|PinConglomerate=56|PinLength=30|Location.X=550|Location.Y=478|Name=6|Designator=C-6|PinPropagationDelay=0.000000E+000
|RECORD=2|OwnerIndex=1698|OwnerPartId=3|FormalType=1|PinConglomerate=58|PinLength=30|Location.X=490|Location.Y=468|Name=7|Designator=C-7|PinPropagationDelay=0.000000E+000
|RECORD=2|OwnerIndex=1698|OwnerPartId=3|FormalType=1|PinConglomerate=56|PinLength=30|Location.X=550|Location.Y=468|Name=8|Designator=C-8|PinPropagationDelay=0.000000E+000
|RECORD=2|OwnerIndex=1698|OwnerPartId=3|FormalType=1|PinConglomerate=58|PinLength=30|Location.X=490|Location.Y=458|Name=9|Designator=C-9|PinPropagationDelay=0.000000E+000
|RECORD=2|OwnerIndex=1698|OwnerPartId=3|FormalType=1|PinConglomerate=56|PinLength=30|Location.X=550|Location.Y=458|Name=10|Designator=C-10|PinPropagationDelay=0.000000E+000
|RECORD=2|OwnerIndex=1698|OwnerPartId=3|FormalType=1|PinConglomerate=58|PinLength=30|Location.X=490|Location.Y=448|Name=11|Designator=C-11|PinPropagationDelay=0.000000E+000
|RECORD=2|OwnerIndex=1698|OwnerPartId=3|FormalType=1|PinConglomerate=56|PinLength=30|Location.X=550|Location.Y=448|Name=12|Designator=C-12|PinPropagationDelay=0.000000E+000
|RECORD=2|OwnerIndex=1698|OwnerPartId=3|FormalType=1|PinConglomerate=58|PinLength=30|Location.X=490|Location.Y=438|Name=13|Designator=C-13|PinPropagationDelay=0.000000E+000
|RECORD=2|OwnerIndex=1698|OwnerPartId=3|FormalType=1|PinConglomerate=56|PinLength=30|Location.X=550|Location.Y=438|Name=14|Designator=C-14|PinPropagationDelay=0.000000E+000
|RECORD=2|OwnerIndex=1698|OwnerPartId=3|FormalType=1|PinConglomerate=58|PinLength=30|Location.X=490|Location.Y=428|Name=15|Designator=C-15|PinPropagationDelay=0.000000E+000
|RECORD=2|OwnerIndex=1698|OwnerPartId=3|FormalType=1|PinConglomerate=56|PinLength=30|Location.X=550|Location.Y=428|Name=16|Designator=C-16|PinPropagationDelay=0.000000E+000
|RECORD=2|OwnerIndex=1698|OwnerPartId=3|FormalType=1|PinConglomerate=58|PinLength=30|Location.X=490|Location.Y=418|Name=17|Designator=C-17|PinPropagationDelay=0.000000E+000
|RECORD=2|OwnerIndex=1698|OwnerPartId=3|FormalType=1|PinConglomerate=56|PinLength=30|Location.X=550|Location.Y=418|Name=18|Designator=C-18|PinPropagationDelay=0.000000E+000
|RECORD=2|OwnerIndex=1698|OwnerPartId=3|FormalType=1|PinConglomerate=58|PinLength=30|Location.X=490|Location.Y=408|Name=19|Designator=C-19|PinPropagationDelay=0.000000E+000
|RECORD=2|OwnerIndex=1698|OwnerPartId=3|FormalType=1|PinConglomerate=56|PinLength=30|Location.X=550|Location.Y=408|Name=20|Designator=C-20|PinPropagationDelay=0.000000E+000
|RECORD=2|OwnerIndex=1698|OwnerPartId=3|FormalType=1|PinConglomerate=58|PinLength=30|Location.X=490|Location.Y=398|Name=21|Designator=C-21|PinPropagationDelay=0.000000E+000
|RECORD=2|OwnerIndex=1698|OwnerPartId=3|FormalType=1|PinConglomerate=56|PinLength=30|Location.X=550|Location.Y=398|Name=22|Designator=C-22|PinPropagationDelay=0.000000E+000
|RECORD=2|OwnerIndex=1698|OwnerPartId=3|FormalType=1|PinConglomerate=58|PinLength=30|Location.X=490|Location.Y=388|Name=23|Designator=C-23|PinPropagationDelay=0.000000E+000
|RECORD=2|OwnerIndex=1698|OwnerPartId=3|FormalType=1|PinConglomerate=56|PinLength=30|Location.X=550|Location.Y=388|Name=24|Designator=C-24|PinPropagationDelay=0.000000E+000
|RECORD=2|OwnerIndex=1698|OwnerPartId=3|FormalType=1|PinConglomerate=58|PinLength=30|Location.X=490|Location.Y=378|Name=25|Designator=C-25|PinPropagationDelay=0.000000E+000
|RECORD=2|OwnerIndex=1698|OwnerPartId=3|FormalType=1|PinConglomerate=56|PinLength=30|Location.X=550|Location.Y=378|Name=26|Designator=C-26|PinPropagationDelay=0.000000E+000
|RECORD=2|OwnerIndex=1698|OwnerPartId=3|FormalType=1|PinConglomerate=58|PinLength=30|Location.X=490|Location.Y=368|Name=27|Designator=C-27|PinPropagationDelay=0.000000E+000
|RECORD=2|OwnerIndex=1698|OwnerPartId=3|FormalType=1|PinConglomerate=56|PinLength=30|Location.X=550|Location.Y=368|Name=28|Designator=C-28|PinPropagationDelay=0.000000E+000
|RECORD=2|OwnerIndex=1698|OwnerPartId=3|FormalType=1|PinConglomerate=58|PinLength=30|Location.X=490|Location.Y=358|Name=29|Designator=C-29|PinPropagationDelay=0.000000E+000
|RECORD=2|OwnerIndex=1698|OwnerPartId=3|FormalType=1|PinConglomerate=56|PinLength=30|Location.X=550|Location.Y=358|Name=30|Designator=C-30|PinPropagationDelay=0.000000E+000
|RECORD=2|OwnerIndex=1698|OwnerPartId=3|FormalType=1|PinConglomerate=58|PinLength=30|Location.X=490|Location.Y=348|Name=31|Designator=C-31|PinPropagationDelay=0.000000E+000
|RECORD=2|OwnerIndex=1698|OwnerPartId=3|FormalType=1|PinConglomerate=56|PinLength=30|Location.X=550|Location.Y=348|Name=32|Designator=C-32|PinPropagationDelay=0.000000E+000
|RECORD=2|OwnerIndex=1698|OwnerPartId=3|FormalType=1|PinConglomerate=58|PinLength=30|Location.X=490|Location.Y=338|Name=33|Designator=C-33|PinPropagationDelay=0.000000E+000
|RECORD=2|OwnerIndex=1698|OwnerPartId=3|FormalType=1|PinConglomerate=56|PinLength=30|Location.X=550|Location.Y=338|Name=34|Designator=C-34|PinPropagationDelay=0.000000E+000
|RECORD=2|OwnerIndex=1698|OwnerPartId=3|FormalType=1|PinConglomerate=58|PinLength=30|Location.X=490|Location.Y=328|Name=35|Designator=C-35|PinPropagationDelay=0.000000E+000
|RECORD=2|OwnerIndex=1698|OwnerPartId=3|FormalType=1|PinConglomerate=56|PinLength=30|Location.X=550|Location.Y=328|Name=36|Designator=C-36|PinPropagationDelay=0.000000E+000
|RECORD=2|OwnerIndex=1698|OwnerPartId=3|FormalType=1|PinConglomerate=58|PinLength=30|Location.X=490|Location.Y=318|Name=37|Designator=C-37|PinPropagationDelay=0.000000E+000
|RECORD=2|OwnerIndex=1698|OwnerPartId=3|FormalType=1|PinConglomerate=56|PinLength=30|Location.X=550|Location.Y=318|Name=38|Designator=C-38|PinPropagationDelay=0.000000E+000
|RECORD=2|OwnerIndex=1698|OwnerPartId=3|FormalType=1|PinConglomerate=58|PinLength=30|Location.X=490|Location.Y=308|Name=39|Designator=C-39|PinPropagationDelay=0.000000E+000
|RECORD=2|OwnerIndex=1698|OwnerPartId=3|FormalType=1|PinConglomerate=56|PinLength=30|Location.X=550|Location.Y=308|Name=40|Designator=C-40|PinPropagationDelay=0.000000E+000
|RECORD=2|OwnerIndex=1698|OwnerPartId=3|FormalType=1|PinConglomerate=58|PinLength=30|Location.X=490|Location.Y=298|Name=41|Designator=C-41|PinPropagationDelay=0.000000E+000
|RECORD=2|OwnerIndex=1698|OwnerPartId=3|FormalType=1|PinConglomerate=56|PinLength=30|Location.X=550|Location.Y=298|Name=42|Designator=C-42|PinPropagationDelay=0.000000E+000
|RECORD=2|OwnerIndex=1698|OwnerPartId=3|FormalType=1|PinConglomerate=58|PinLength=30|Location.X=490|Location.Y=288|Name=43|Designator=C-43|PinPropagationDelay=0.000000E+000
|RECORD=2|OwnerIndex=1698|OwnerPartId=3|FormalType=1|PinConglomerate=56|PinLength=30|Location.X=550|Location.Y=288|Name=44|Designator=C-44|PinPropagationDelay=0.000000E+000
|RECORD=2|OwnerIndex=1698|OwnerPartId=3|FormalType=1|PinConglomerate=58|PinLength=30|Location.X=490|Location.Y=278|Name=45|Designator=C-45|PinPropagationDelay=0.000000E+000
|RECORD=2|OwnerIndex=1698|OwnerPartId=3|FormalType=1|PinConglomerate=56|PinLength=30|Location.X=550|Location.Y=278|Name=46|Designator=C-46|PinPropagationDelay=0.000000E+000
|RECORD=2|OwnerIndex=1698|OwnerPartId=3|FormalType=1|PinConglomerate=58|PinLength=30|Location.X=490|Location.Y=268|Name=47|Designator=C-47|PinPropagationDelay=0.000000E+000
|RECORD=2|OwnerIndex=1698|OwnerPartId=3|FormalType=1|PinConglomerate=56|PinLength=30|Location.X=550|Location.Y=268|Name=48|Designator=C-48|PinPropagationDelay=0.000000E+000
|RECORD=2|OwnerIndex=1698|OwnerPartId=3|FormalType=1|PinConglomerate=58|PinLength=30|Location.X=490|Location.Y=258|Name=49|Designator=C-49|PinPropagationDelay=0.000000E+000
|RECORD=2|OwnerIndex=1698|OwnerPartId=3|FormalType=1|PinConglomerate=56|PinLength=30|Location.X=550|Location.Y=258|Name=50|Designator=C-50|PinPropagationDelay=0.000000E+000
|RECORD=2|OwnerIndex=1698|OwnerPartId=3|FormalType=1|PinConglomerate=58|PinLength=30|Location.X=490|Location.Y=248|Name=51|Designator=C-51|PinPropagationDelay=0.000000E+000
|RECORD=2|OwnerIndex=1698|OwnerPartId=3|FormalType=1|PinConglomerate=56|PinLength=30|Location.X=550|Location.Y=248|Name=52|Designator=C-52|PinPropagationDelay=0.000000E+000
|RECORD=2|OwnerIndex=1698|OwnerPartId=3|FormalType=1|PinConglomerate=58|PinLength=30|Location.X=490|Location.Y=238|Name=53|Designator=C-53|PinPropagationDelay=0.000000E+000
|RECORD=2|OwnerIndex=1698|OwnerPartId=3|FormalType=1|PinConglomerate=56|PinLength=30|Location.X=550|Location.Y=238|Name=54|Designator=C-54|PinPropagationDelay=0.000000E+000
|RECORD=2|OwnerIndex=1698|OwnerPartId=3|FormalType=1|PinConglomerate=58|PinLength=30|Location.X=490|Location.Y=228|Name=55|Designator=C-55|PinPropagationDelay=0.000000E+000
|RECORD=2|OwnerIndex=1698|OwnerPartId=3|FormalType=1|PinConglomerate=56|PinLength=30|Location.X=550|Location.Y=228|Name=56|Designator=C-56|PinPropagationDelay=0.000000E+000
|RECORD=2|OwnerIndex=1698|OwnerPartId=3|FormalType=1|PinConglomerate=58|PinLength=30|Location.X=490|Location.Y=218|Name=57|Designator=C-57|PinPropagationDelay=0.000000E+000
|RECORD=2|OwnerIndex=1698|OwnerPartId=3|FormalType=1|PinConglomerate=56|PinLength=30|Location.X=550|Location.Y=218|Name=58|Designator=C-58|PinPropagationDelay=0.000000E+000
|RECORD=2|OwnerIndex=1698|OwnerPartId=3|FormalType=1|PinConglomerate=58|PinLength=30|Location.X=490|Location.Y=208|Name=59|Designator=C-59|PinPropagationDelay=0.000000E+000
|RECORD=2|OwnerIndex=1698|OwnerPartId=3|FormalType=1|PinConglomerate=56|PinLength=30|Location.X=550|Location.Y=208|Name=60|Designator=C-60|PinPropagationDelay=0.000000E+000
|RECORD=2|OwnerIndex=1698|OwnerPartId=3|FormalType=1|PinConglomerate=58|PinLength=30|Location.X=490|Location.Y=198|Name=61|Designator=C-61|PinPropagationDelay=0.000000E+000
|RECORD=2|OwnerIndex=1698|OwnerPartId=3|FormalType=1|PinConglomerate=56|PinLength=30|Location.X=550|Location.Y=198|Name=62|Designator=C-62|PinPropagationDelay=0.000000E+000
|RECORD=2|OwnerIndex=1698|OwnerPartId=3|FormalType=1|PinConglomerate=58|PinLength=30|Location.X=490|Location.Y=188|Name=63|Designator=C-63|PinPropagationDelay=0.000000E+000
|RECORD=2|OwnerIndex=1698|OwnerPartId=3|FormalType=1|PinConglomerate=56|PinLength=30|Location.X=550|Location.Y=188|Name=64|Designator=C-64|PinPropagationDelay=0.000000E+000
|RECORD=2|OwnerIndex=1698|OwnerPartId=3|FormalType=1|PinConglomerate=58|PinLength=30|Location.X=490|Location.Y=178|Name=65|Designator=C-65|PinPropagationDelay=0.000000E+000
|RECORD=2|OwnerIndex=1698|OwnerPartId=3|FormalType=1|PinConglomerate=56|PinLength=30|Location.X=550|Location.Y=178|Name=66|Designator=C-66|PinPropagationDelay=0.000000E+000
|RECORD=2|OwnerIndex=1698|OwnerPartId=3|FormalType=1|PinConglomerate=58|PinLength=30|Location.X=490|Location.Y=168|Name=67|Designator=C-67|PinPropagationDelay=0.000000E+000
|RECORD=2|OwnerIndex=1698|OwnerPartId=3|FormalType=1|PinConglomerate=56|PinLength=30|Location.X=550|Location.Y=168|Name=68|Designator=C-68|PinPropagationDelay=0.000000E+000
|RECORD=2|OwnerIndex=1698|OwnerPartId=3|FormalType=1|PinConglomerate=58|PinLength=30|Location.X=490|Location.Y=158|Name=69|Designator=C-69|PinPropagationDelay=0.000000E+000
|RECORD=2|OwnerIndex=1698|OwnerPartId=3|FormalType=1|PinConglomerate=56|PinLength=30|Location.X=550|Location.Y=158|Name=70|Designator=C-70|PinPropagationDelay=0.000000E+000
|RECORD=2|OwnerIndex=1698|OwnerPartId=3|FormalType=1|PinConglomerate=58|PinLength=30|Location.X=490|Location.Y=148|Name=71|Designator=C-71|PinPropagationDelay=0.000000E+000
|RECORD=2|OwnerIndex=1698|OwnerPartId=3|FormalType=1|PinConglomerate=56|PinLength=30|Location.X=550|Location.Y=148|Name=72|Designator=C-72|PinPropagationDelay=0.000000E+000
|RECORD=2|OwnerIndex=1698|OwnerPartId=3|FormalType=1|PinConglomerate=58|PinLength=30|Location.X=490|Location.Y=138|Name=73|Designator=C-73|PinPropagationDelay=0.000000E+000
|RECORD=2|OwnerIndex=1698|OwnerPartId=3|FormalType=1|PinConglomerate=56|PinLength=30|Location.X=550|Location.Y=138|Name=74|Designator=C-74|PinPropagationDelay=0.000000E+000
|RECORD=2|OwnerIndex=1698|OwnerPartId=3|FormalType=1|PinConglomerate=58|PinLength=30|Location.X=490|Location.Y=128|Name=75|Designator=C-75|PinPropagationDelay=0.000000E+000
|RECORD=2|OwnerIndex=1698|OwnerPartId=3|FormalType=1|PinConglomerate=56|PinLength=30|Location.X=550|Location.Y=128|Name=76|Designator=C-76|PinPropagationDelay=0.000000E+000
|RECORD=2|OwnerIndex=1698|OwnerPartId=3|FormalType=1|PinConglomerate=58|PinLength=30|Location.X=490|Location.Y=118|Name=77|Designator=C-77|PinPropagationDelay=0.000000E+000
|RECORD=2|OwnerIndex=1698|OwnerPartId=3|FormalType=1|PinConglomerate=56|PinLength=30|Location.X=550|Location.Y=118|Name=78|Designator=C-78|PinPropagationDelay=0.000000E+000
|RECORD=2|OwnerIndex=1698|OwnerPartId=3|FormalType=1|PinConglomerate=58|PinLength=30|Location.X=490|Location.Y=108|Name=79|Designator=C-79|PinPropagationDelay=0.000000E+000
|RECORD=2|OwnerIndex=1698|OwnerPartId=3|FormalType=1|PinConglomerate=56|PinLength=30|Location.X=550|Location.Y=108|Name=80|Designator=C-80|PinPropagationDelay=0.000000E+000
|RECORD=2|OwnerIndex=1698|OwnerPartId=3|FormalType=1|PinConglomerate=58|PinLength=30|Location.X=490|Location.Y=98|Name=81|Designator=C-81|PinPropagationDelay=0.000000E+000
|RECORD=2|OwnerIndex=1698|OwnerPartId=3|FormalType=1|PinConglomerate=56|PinLength=30|Location.X=550|Location.Y=98|Name=82|Designator=C-82|PinPropagationDelay=0.000000E+000
|RECORD=2|OwnerIndex=1698|OwnerPartId=3|FormalType=1|PinConglomerate=58|PinLength=30|Location.X=490|Location.Y=88|Name=83|Designator=C-83|PinPropagationDelay=0.000000E+000
|RECORD=2|OwnerIndex=1698|OwnerPartId=3|FormalType=1|PinConglomerate=56|PinLength=30|Location.X=550|Location.Y=88|Name=84|Designator=C-84|PinPropagationDelay=0.000000E+000
|RECORD=14|OwnerIndex=1698|IsNotAccesible=T|IndexInSheet=170|OwnerPartId=4|Location.X=490|Location.Y=78|Corner.X=550|Corner.Y=508|Color=128|AreaColor=11599871|IsSolid=T
|RECORD=2|OwnerIndex=1698|OwnerPartId=4|FormalType=1|PinConglomerate=58|PinLength=30|Location.X=490|Location.Y=498|Name=1|Designator=D-1|PinPropagationDelay=0.000000E+000
|RECORD=2|OwnerIndex=1698|OwnerPartId=4|FormalType=1|PinConglomerate=56|PinLength=30|Location.X=550|Location.Y=498|Name=2|Designator=D-2|PinPropagationDelay=0.000000E+000
|RECORD=2|OwnerIndex=1698|OwnerPartId=4|FormalType=1|PinConglomerate=58|PinLength=30|Location.X=490|Location.Y=488|Name=3|Designator=D-3|PinPropagationDelay=0.000000E+000
|RECORD=2|OwnerIndex=1698|OwnerPartId=4|FormalType=1|PinConglomerate=56|PinLength=30|Location.X=550|Location.Y=488|Name=4|Designator=D-4|PinPropagationDelay=0.000000E+000
|RECORD=2|OwnerIndex=1698|OwnerPartId=4|FormalType=1|PinConglomerate=58|PinLength=30|Location.X=490|Location.Y=478|Name=5|Designator=D-5|PinPropagationDelay=0.000000E+000
|RECORD=2|OwnerIndex=1698|OwnerPartId=4|FormalType=1|PinConglomerate=56|PinLength=30|Location.X=550|Location.Y=478|Name=6|Designator=D-6|PinPropagationDelay=0.000000E+000
|RECORD=2|OwnerIndex=1698|OwnerPartId=4|FormalType=1|PinConglomerate=58|PinLength=30|Location.X=490|Location.Y=468|Name=7|Designator=D-7|PinPropagationDelay=0.000000E+000
|RECORD=2|OwnerIndex=1698|OwnerPartId=4|FormalType=1|PinConglomerate=56|PinLength=30|Location.X=550|Location.Y=468|Name=8|Designator=D-8|PinPropagationDelay=0.000000E+000
|RECORD=2|OwnerIndex=1698|OwnerPartId=4|FormalType=1|PinConglomerate=58|PinLength=30|Location.X=490|Location.Y=458|Name=9|Designator=D-9|PinPropagationDelay=0.000000E+000
|RECORD=2|OwnerIndex=1698|OwnerPartId=4|FormalType=1|PinConglomerate=56|PinLength=30|Location.X=550|Location.Y=458|Name=10|Designator=D-10|PinPropagationDelay=0.000000E+000
|RECORD=2|OwnerIndex=1698|OwnerPartId=4|FormalType=1|PinConglomerate=58|PinLength=30|Location.X=490|Location.Y=448|Name=11|Designator=D-11|PinPropagationDelay=0.000000E+000
|RECORD=2|OwnerIndex=1698|OwnerPartId=4|FormalType=1|PinConglomerate=56|PinLength=30|Location.X=550|Location.Y=448|Name=12|Designator=D-12|PinPropagationDelay=0.000000E+000
|RECORD=2|OwnerIndex=1698|OwnerPartId=4|FormalType=1|PinConglomerate=58|PinLength=30|Location.X=490|Location.Y=438|Name=13|Designator=D-13|PinPropagationDelay=0.000000E+000
|RECORD=2|OwnerIndex=1698|OwnerPartId=4|FormalType=1|PinConglomerate=56|PinLength=30|Location.X=550|Location.Y=438|Name=14|Designator=D-14|PinPropagationDelay=0.000000E+000
|RECORD=2|OwnerIndex=1698|OwnerPartId=4|FormalType=1|PinConglomerate=58|PinLength=30|Location.X=490|Location.Y=428|Name=15|Designator=D-15|PinPropagationDelay=0.000000E+000
|RECORD=2|OwnerIndex=1698|OwnerPartId=4|FormalType=1|PinConglomerate=56|PinLength=30|Location.X=550|Location.Y=428|Name=16|Designator=D-16|PinPropagationDelay=0.000000E+000
|RECORD=2|OwnerIndex=1698|OwnerPartId=4|FormalType=1|PinConglomerate=58|PinLength=30|Location.X=490|Location.Y=418|Name=17|Designator=D-17|PinPropagationDelay=0.000000E+000
|RECORD=2|OwnerIndex=1698|OwnerPartId=4|FormalType=1|PinConglomerate=56|PinLength=30|Location.X=550|Location.Y=418|Name=18|Designator=D-18|PinPropagationDelay=0.000000E+000
|RECORD=2|OwnerIndex=1698|OwnerPartId=4|FormalType=1|PinConglomerate=58|PinLength=30|Location.X=490|Location.Y=408|Name=19|Designator=D-19|PinPropagationDelay=0.000000E+000
|RECORD=2|OwnerIndex=1698|OwnerPartId=4|FormalType=1|PinConglomerate=56|PinLength=30|Location.X=550|Location.Y=408|Name=20|Designator=D-20|PinPropagationDelay=0.000000E+000
|RECORD=2|OwnerIndex=1698|OwnerPartId=4|FormalType=1|PinConglomerate=58|PinLength=30|Location.X=490|Location.Y=398|Name=21|Designator=D-21|PinPropagationDelay=0.000000E+000
|RECORD=2|OwnerIndex=1698|OwnerPartId=4|FormalType=1|PinConglomerate=56|PinLength=30|Location.X=550|Location.Y=398|Name=22|Designator=D-22|PinPropagationDelay=0.000000E+000
|RECORD=2|OwnerIndex=1698|OwnerPartId=4|FormalType=1|PinConglomerate=58|PinLength=30|Location.X=490|Location.Y=388|Name=23|Designator=D-23|PinPropagationDelay=0.000000E+000
|RECORD=2|OwnerIndex=1698|OwnerPartId=4|FormalType=1|PinConglomerate=56|PinLength=30|Location.X=550|Location.Y=388|Name=24|Designator=D-24|PinPropagationDelay=0.000000E+000
|RECORD=2|OwnerIndex=1698|OwnerPartId=4|FormalType=1|PinConglomerate=58|PinLength=30|Location.X=490|Location.Y=378|Name=25|Designator=D-25|PinPropagationDelay=0.000000E+000
|RECORD=2|OwnerIndex=1698|OwnerPartId=4|FormalType=1|PinConglomerate=56|PinLength=30|Location.X=550|Location.Y=378|Name=26|Designator=D-26|PinPropagationDelay=0.000000E+000
|RECORD=2|OwnerIndex=1698|OwnerPartId=4|FormalType=1|PinConglomerate=58|PinLength=30|Location.X=490|Location.Y=368|Name=27|Designator=D-27|PinPropagationDelay=0.000000E+000
|RECORD=2|OwnerIndex=1698|OwnerPartId=4|FormalType=1|PinConglomerate=56|PinLength=30|Location.X=550|Location.Y=368|Name=28|Designator=D-28|PinPropagationDelay=0.000000E+000
|RECORD=2|OwnerIndex=1698|OwnerPartId=4|FormalType=1|PinConglomerate=58|PinLength=30|Location.X=490|Location.Y=358|Name=29|Designator=D-29|PinPropagationDelay=0.000000E+000
|RECORD=2|OwnerIndex=1698|OwnerPartId=4|FormalType=1|PinConglomerate=56|PinLength=30|Location.X=550|Location.Y=358|Name=30|Designator=D-30|PinPropagationDelay=0.000000E+000
|RECORD=2|OwnerIndex=1698|OwnerPartId=4|FormalType=1|PinConglomerate=58|PinLength=30|Location.X=490|Location.Y=348|Name=31|Designator=D-31|PinPropagationDelay=0.000000E+000
|RECORD=2|OwnerIndex=1698|OwnerPartId=4|FormalType=1|PinConglomerate=56|PinLength=30|Location.X=550|Location.Y=348|Name=32|Designator=D-32|PinPropagationDelay=0.000000E+000
|RECORD=2|OwnerIndex=1698|OwnerPartId=4|FormalType=1|PinConglomerate=58|PinLength=30|Location.X=490|Location.Y=338|Name=33|Designator=D-33|PinPropagationDelay=0.000000E+000
|RECORD=2|OwnerIndex=1698|OwnerPartId=4|FormalType=1|PinConglomerate=56|PinLength=30|Location.X=550|Location.Y=338|Name=34|Designator=D-34|PinPropagationDelay=0.000000E+000
|RECORD=2|OwnerIndex=1698|OwnerPartId=4|FormalType=1|PinConglomerate=58|PinLength=30|Location.X=490|Location.Y=328|Name=35|Designator=D-35|PinPropagationDelay=0.000000E+000
|RECORD=2|OwnerIndex=1698|OwnerPartId=4|FormalType=1|PinConglomerate=56|PinLength=30|Location.X=550|Location.Y=328|Name=36|Designator=D-36|PinPropagationDelay=0.000000E+000
|RECORD=2|OwnerIndex=1698|OwnerPartId=4|FormalType=1|PinConglomerate=58|PinLength=30|Location.X=490|Location.Y=318|Name=37|Designator=D-37|PinPropagationDelay=0.000000E+000
|RECORD=2|OwnerIndex=1698|OwnerPartId=4|FormalType=1|PinConglomerate=56|PinLength=30|Location.X=550|Location.Y=318|Name=38|Designator=D-38|PinPropagationDelay=0.000000E+000
|RECORD=2|OwnerIndex=1698|OwnerPartId=4|FormalType=1|PinConglomerate=58|PinLength=30|Location.X=490|Location.Y=308|Name=39|Designator=D-39|PinPropagationDelay=0.000000E+000
|RECORD=2|OwnerIndex=1698|OwnerPartId=4|FormalType=1|PinConglomerate=56|PinLength=30|Location.X=550|Location.Y=308|Name=40|Designator=D-40|PinPropagationDelay=0.000000E+000
|RECORD=2|OwnerIndex=1698|OwnerPartId=4|FormalType=1|PinConglomerate=58|PinLength=30|Location.X=490|Location.Y=298|Name=41|Designator=D-41|PinPropagationDelay=0.000000E+000
|RECORD=2|OwnerIndex=1698|OwnerPartId=4|FormalType=1|PinConglomerate=56|PinLength=30|Location.X=550|Location.Y=298|Name=42|Designator=D-42|PinPropagationDelay=0.000000E+000
|RECORD=2|OwnerIndex=1698|OwnerPartId=4|FormalType=1|PinConglomerate=58|PinLength=30|Location.X=490|Location.Y=288|Name=43|Designator=D-43|PinPropagationDelay=0.000000E+000
|RECORD=2|OwnerIndex=1698|OwnerPartId=4|FormalType=1|PinConglomerate=56|PinLength=30|Location.X=550|Location.Y=288|Name=44|Designator=D-44|PinPropagationDelay=0.000000E+000
|RECORD=2|OwnerIndex=1698|OwnerPartId=4|FormalType=1|PinConglomerate=58|PinLength=30|Location.X=490|Location.Y=278|Name=45|Designator=D-45|PinPropagationDelay=0.000000E+000
|RECORD=2|OwnerIndex=1698|OwnerPartId=4|FormalType=1|PinConglomerate=56|PinLength=30|Location.X=550|Location.Y=278|Name=46|Designator=D-46|PinPropagationDelay=0.000000E+000
|RECORD=2|OwnerIndex=1698|OwnerPartId=4|FormalType=1|PinConglomerate=58|PinLength=30|Location.X=490|Location.Y=268|Name=47|Designator=D-47|PinPropagationDelay=0.000000E+000
|RECORD=2|OwnerIndex=1698|OwnerPartId=4|FormalType=1|PinConglomerate=56|PinLength=30|Location.X=550|Location.Y=268|Name=48|Designator=D-48|PinPropagationDelay=0.000000E+000
|RECORD=2|OwnerIndex=1698|OwnerPartId=4|FormalType=1|PinConglomerate=58|PinLength=30|Location.X=490|Location.Y=258|Name=49|Designator=D-49|PinPropagationDelay=0.000000E+000
|RECORD=2|OwnerIndex=1698|OwnerPartId=4|FormalType=1|PinConglomerate=56|PinLength=30|Location.X=550|Location.Y=258|Name=50|Designator=D-50|PinPropagationDelay=0.000000E+000
|RECORD=2|OwnerIndex=1698|OwnerPartId=4|FormalType=1|PinConglomerate=58|PinLength=30|Location.X=490|Location.Y=248|Name=51|Designator=D-51|PinPropagationDelay=0.000000E+000
|RECORD=2|OwnerIndex=1698|OwnerPartId=4|FormalType=1|PinConglomerate=56|PinLength=30|Location.X=550|Location.Y=248|Name=52|Designator=D-52|PinPropagationDelay=0.000000E+000
|RECORD=2|OwnerIndex=1698|OwnerPartId=4|FormalType=1|PinConglomerate=58|PinLength=30|Location.X=490|Location.Y=238|Name=53|Designator=D-53|PinPropagationDelay=0.000000E+000
|RECORD=2|OwnerIndex=1698|OwnerPartId=4|FormalType=1|PinConglomerate=56|PinLength=30|Location.X=550|Location.Y=238|Name=54|Designator=D-54|PinPropagationDelay=0.000000E+000
|RECORD=2|OwnerIndex=1698|OwnerPartId=4|FormalType=1|PinConglomerate=58|PinLength=30|Location.X=490|Location.Y=228|Name=55|Designator=D-55|PinPropagationDelay=0.000000E+000
|RECORD=2|OwnerIndex=1698|OwnerPartId=4|FormalType=1|PinConglomerate=56|PinLength=30|Location.X=550|Location.Y=228|Name=56|Designator=D-56|PinPropagationDelay=0.000000E+000
|RECORD=2|OwnerIndex=1698|OwnerPartId=4|FormalType=1|PinConglomerate=58|PinLength=30|Location.X=490|Location.Y=218|Name=57|Designator=D-57|PinPropagationDelay=0.000000E+000
|RECORD=2|OwnerIndex=1698|OwnerPartId=4|FormalType=1|PinConglomerate=56|PinLength=30|Location.X=550|Location.Y=218|Name=58|Designator=D-58|PinPropagationDelay=0.000000E+000
|RECORD=2|OwnerIndex=1698|OwnerPartId=4|FormalType=1|PinConglomerate=58|PinLength=30|Location.X=490|Location.Y=208|Name=59|Designator=D-59|PinPropagationDelay=0.000000E+000
|RECORD=2|OwnerIndex=1698|OwnerPartId=4|FormalType=1|PinConglomerate=56|PinLength=30|Location.X=550|Location.Y=208|Name=60|Designator=D-60|PinPropagationDelay=0.000000E+000
|RECORD=2|OwnerIndex=1698|OwnerPartId=4|FormalType=1|PinConglomerate=58|PinLength=30|Location.X=490|Location.Y=198|Name=61|Designator=D-61|PinPropagationDelay=0.000000E+000
|RECORD=2|OwnerIndex=1698|OwnerPartId=4|FormalType=1|PinConglomerate=56|PinLength=30|Location.X=550|Location.Y=198|Name=62|Designator=D-62|PinPropagationDelay=0.000000E+000
|RECORD=2|OwnerIndex=1698|OwnerPartId=4|FormalType=1|PinConglomerate=58|PinLength=30|Location.X=490|Location.Y=188|Name=63|Designator=D-63|PinPropagationDelay=0.000000E+000
|RECORD=2|OwnerIndex=1698|OwnerPartId=4|FormalType=1|PinConglomerate=56|PinLength=30|Location.X=550|Location.Y=188|Name=64|Designator=D-64|PinPropagationDelay=0.000000E+000
|RECORD=2|OwnerIndex=1698|OwnerPartId=4|FormalType=1|PinConglomerate=58|PinLength=30|Location.X=490|Location.Y=178|Name=65|Designator=D-65|PinPropagationDelay=0.000000E+000
|RECORD=2|OwnerIndex=1698|OwnerPartId=4|FormalType=1|PinConglomerate=56|PinLength=30|Location.X=550|Location.Y=178|Name=66|Designator=D-66|PinPropagationDelay=0.000000E+000
|RECORD=2|OwnerIndex=1698|OwnerPartId=4|FormalType=1|PinConglomerate=58|PinLength=30|Location.X=490|Location.Y=168|Name=67|Designator=D-67|PinPropagationDelay=0.000000E+000
|RECORD=2|OwnerIndex=1698|OwnerPartId=4|FormalType=1|PinConglomerate=56|PinLength=30|Location.X=550|Location.Y=168|Name=68|Designator=D-68|PinPropagationDelay=0.000000E+000
|RECORD=2|OwnerIndex=1698|OwnerPartId=4|FormalType=1|PinConglomerate=58|PinLength=30|Location.X=490|Location.Y=158|Name=69|Designator=D-69|PinPropagationDelay=0.000000E+000
|RECORD=2|OwnerIndex=1698|OwnerPartId=4|FormalType=1|PinConglomerate=56|PinLength=30|Location.X=550|Location.Y=158|Name=70|Designator=D-70|PinPropagationDelay=0.000000E+000
|RECORD=2|OwnerIndex=1698|OwnerPartId=4|FormalType=1|PinConglomerate=58|PinLength=30|Location.X=490|Location.Y=148|Name=71|Designator=D-71|PinPropagationDelay=0.000000E+000
|RECORD=2|OwnerIndex=1698|OwnerPartId=4|FormalType=1|PinConglomerate=56|PinLength=30|Location.X=550|Location.Y=148|Name=72|Designator=D-72|PinPropagationDelay=0.000000E+000
|RECORD=2|OwnerIndex=1698|OwnerPartId=4|FormalType=1|PinConglomerate=58|PinLength=30|Location.X=490|Location.Y=138|Name=73|Designator=D-73|PinPropagationDelay=0.000000E+000
|RECORD=2|OwnerIndex=1698|OwnerPartId=4|FormalType=1|PinConglomerate=56|PinLength=30|Location.X=550|Location.Y=138|Name=74|Designator=D-74|PinPropagationDelay=0.000000E+000
|RECORD=2|OwnerIndex=1698|OwnerPartId=4|FormalType=1|PinConglomerate=58|PinLength=30|Location.X=490|Location.Y=128|Name=75|Designator=D-75|PinPropagationDelay=0.000000E+000
|RECORD=2|OwnerIndex=1698|OwnerPartId=4|FormalType=1|PinConglomerate=56|PinLength=30|Location.X=550|Location.Y=128|Name=76|Designator=D-76|PinPropagationDelay=0.000000E+000
|RECORD=2|OwnerIndex=1698|OwnerPartId=4|FormalType=1|PinConglomerate=58|PinLength=30|Location.X=490|Location.Y=118|Name=77|Designator=D-77|PinPropagationDelay=0.000000E+000
|RECORD=2|OwnerIndex=1698|OwnerPartId=4|FormalType=1|PinConglomerate=56|PinLength=30|Location.X=550|Location.Y=118|Name=78|Designator=D-78|PinPropagationDelay=0.000000E+000
|RECORD=2|OwnerIndex=1698|OwnerPartId=4|FormalType=1|PinConglomerate=58|PinLength=30|Location.X=490|Location.Y=108|Name=79|Designator=D-79|PinPropagationDelay=0.000000E+000
|RECORD=2|OwnerIndex=1698|OwnerPartId=4|FormalType=1|PinConglomerate=56|PinLength=30|Location.X=550|Location.Y=108|Name=80|Designator=D-80|PinPropagationDelay=0.000000E+000
|RECORD=2|OwnerIndex=1698|OwnerPartId=4|FormalType=1|PinConglomerate=58|PinLength=30|Location.X=490|Location.Y=98|Name=81|Designator=D-81|PinPropagationDelay=0.000000E+000
|RECORD=2|OwnerIndex=1698|OwnerPartId=4|FormalType=1|PinConglomerate=56|PinLength=30|Location.X=550|Location.Y=98|Name=82|Designator=D-82|PinPropagationDelay=0.000000E+000
|RECORD=2|OwnerIndex=1698|OwnerPartId=4|FormalType=1|PinConglomerate=58|PinLength=30|Location.X=490|Location.Y=88|Name=83|Designator=D-83|PinPropagationDelay=0.000000E+000
|RECORD=2|OwnerIndex=1698|OwnerPartId=4|FormalType=1|PinConglomerate=56|PinLength=30|Location.X=550|Location.Y=88|Name=84|Designator=D-84|PinPropagationDelay=0.000000E+000
|RECORD=14|OwnerIndex=1698|IsNotAccesible=T|IndexInSheet=255|OwnerPartId=1|Location.X=490|Location.Y=78|Corner.X=550|Corner.Y=508|Color=128|AreaColor=11599871|IsSolid=T
|RECORD=2|OwnerIndex=1698|OwnerPartId=1|FormalType=1|PinConglomerate=58|PinLength=30|Location.X=490|Location.Y=498|Name=1|Designator=A-1|PinPropagationDelay=0.000000E+000
|RECORD=2|OwnerIndex=1698|OwnerPartId=1|FormalType=1|PinConglomerate=56|PinLength=30|Location.X=550|Location.Y=498|Name=2|Designator=A-2|PinPropagationDelay=0.000000E+000
|RECORD=2|OwnerIndex=1698|OwnerPartId=1|FormalType=1|PinConglomerate=58|PinLength=30|Location.X=490|Location.Y=488|Name=3|Designator=A-3|PinPropagationDelay=0.000000E+000
|RECORD=2|OwnerIndex=1698|OwnerPartId=1|FormalType=1|PinConglomerate=56|PinLength=30|Location.X=550|Location.Y=488|Name=4|Designator=A-4|PinPropagationDelay=0.000000E+000
|RECORD=2|OwnerIndex=1698|OwnerPartId=1|FormalType=1|PinConglomerate=58|PinLength=30|Location.X=490|Location.Y=478|Name=5|Designator=A-5|PinPropagationDelay=0.000000E+000
|RECORD=2|OwnerIndex=1698|OwnerPartId=1|FormalType=1|PinConglomerate=56|PinLength=30|Location.X=550|Location.Y=478|Name=6|Designator=A-6|PinPropagationDelay=0.000000E+000
|RECORD=2|OwnerIndex=1698|OwnerPartId=1|FormalType=1|PinConglomerate=58|PinLength=30|Location.X=490|Location.Y=468|Name=7|Designator=A-7|PinPropagationDelay=0.000000E+000
|RECORD=2|OwnerIndex=1698|OwnerPartId=1|FormalType=1|PinConglomerate=56|PinLength=30|Location.X=550|Location.Y=468|Name=8|Designator=A-8|PinPropagationDelay=0.000000E+000
|RECORD=2|OwnerIndex=1698|OwnerPartId=1|FormalType=1|PinConglomerate=58|PinLength=30|Location.X=490|Location.Y=458|Name=9|Designator=A-9|PinPropagationDelay=0.000000E+000
|RECORD=2|OwnerIndex=1698|OwnerPartId=1|FormalType=1|PinConglomerate=56|PinLength=30|Location.X=550|Location.Y=458|Name=10|Designator=A-10|PinPropagationDelay=0.000000E+000
|RECORD=2|OwnerIndex=1698|OwnerPartId=1|FormalType=1|PinConglomerate=58|PinLength=30|Location.X=490|Location.Y=448|Name=11|Designator=A-11|PinPropagationDelay=0.000000E+000
|RECORD=2|OwnerIndex=1698|OwnerPartId=1|FormalType=1|PinConglomerate=56|PinLength=30|Location.X=550|Location.Y=448|Name=12|Designator=A-12|PinPropagationDelay=0.000000E+000
|RECORD=2|OwnerIndex=1698|OwnerPartId=1|FormalType=1|PinConglomerate=58|PinLength=30|Location.X=490|Location.Y=438|Name=13|Designator=A-13|PinPropagationDelay=0.000000E+000
|RECORD=2|OwnerIndex=1698|OwnerPartId=1|FormalType=1|PinConglomerate=56|PinLength=30|Location.X=550|Location.Y=438|Name=14|Designator=A-14|PinPropagationDelay=0.000000E+000
|RECORD=2|OwnerIndex=1698|OwnerPartId=1|FormalType=1|PinConglomerate=58|PinLength=30|Location.X=490|Location.Y=428|Name=15|Designator=A-15|PinPropagationDelay=0.000000E+000
|RECORD=2|OwnerIndex=1698|OwnerPartId=1|FormalType=1|PinConglomerate=56|PinLength=30|Location.X=550|Location.Y=428|Name=16|Designator=A-16|PinPropagationDelay=0.000000E+000
|RECORD=2|OwnerIndex=1698|OwnerPartId=1|FormalType=1|PinConglomerate=58|PinLength=30|Location.X=490|Location.Y=418|Name=17|Designator=A-17|PinPropagationDelay=0.000000E+000
|RECORD=2|OwnerIndex=1698|OwnerPartId=1|FormalType=1|PinConglomerate=56|PinLength=30|Location.X=550|Location.Y=418|Name=18|Designator=A-18|PinPropagationDelay=0.000000E+000
|RECORD=2|OwnerIndex=1698|OwnerPartId=1|FormalType=1|PinConglomerate=58|PinLength=30|Location.X=490|Location.Y=408|Name=19|Designator=A-19|PinPropagationDelay=0.000000E+000
|RECORD=2|OwnerIndex=1698|OwnerPartId=1|FormalType=1|PinConglomerate=56|PinLength=30|Location.X=550|Location.Y=408|Name=20|Designator=A-20|PinPropagationDelay=0.000000E+000
|RECORD=2|OwnerIndex=1698|OwnerPartId=1|FormalType=1|PinConglomerate=58|PinLength=30|Location.X=490|Location.Y=398|Name=21|Designator=A-21|PinPropagationDelay=0.000000E+000
|RECORD=2|OwnerIndex=1698|OwnerPartId=1|FormalType=1|PinConglomerate=56|PinLength=30|Location.X=550|Location.Y=398|Name=22|Designator=A-22|PinPropagationDelay=0.000000E+000
|RECORD=2|OwnerIndex=1698|OwnerPartId=1|FormalType=1|PinConglomerate=58|PinLength=30|Location.X=490|Location.Y=388|Name=23|Designator=A-23|PinPropagationDelay=0.000000E+000
|RECORD=2|OwnerIndex=1698|OwnerPartId=1|FormalType=1|PinConglomerate=56|PinLength=30|Location.X=550|Location.Y=388|Name=24|Designator=A-24|PinPropagationDelay=0.000000E+000
|RECORD=2|OwnerIndex=1698|OwnerPartId=1|FormalType=1|PinConglomerate=58|PinLength=30|Location.X=490|Location.Y=378|Name=25|Designator=A-25|PinPropagationDelay=0.000000E+000
|RECORD=2|OwnerIndex=1698|OwnerPartId=1|FormalType=1|PinConglomerate=56|PinLength=30|Location.X=550|Location.Y=378|Name=26|Designator=A-26|PinPropagationDelay=0.000000E+000
|RECORD=2|OwnerIndex=1698|OwnerPartId=1|FormalType=1|PinConglomerate=58|PinLength=30|Location.X=490|Location.Y=368|Name=27|Designator=A-27|PinPropagationDelay=0.000000E+000
|RECORD=2|OwnerIndex=1698|OwnerPartId=1|FormalType=1|PinConglomerate=56|PinLength=30|Location.X=550|Location.Y=368|Name=28|Designator=A-28|PinPropagationDelay=0.000000E+000
|RECORD=2|OwnerIndex=1698|OwnerPartId=1|FormalType=1|PinConglomerate=58|PinLength=30|Location.X=490|Location.Y=358|Name=29|Designator=A-29|PinPropagationDelay=0.000000E+000
|RECORD=2|OwnerIndex=1698|OwnerPartId=1|FormalType=1|PinConglomerate=56|PinLength=30|Location.X=550|Location.Y=358|Name=30|Designator=A-30|PinPropagationDelay=0.000000E+000
|RECORD=2|OwnerIndex=1698|OwnerPartId=1|FormalType=1|PinConglomerate=58|PinLength=30|Location.X=490|Location.Y=348|Name=31|Designator=A-31|PinPropagationDelay=0.000000E+000
|RECORD=2|OwnerIndex=1698|OwnerPartId=1|FormalType=1|PinConglomerate=56|PinLength=30|Location.X=550|Location.Y=348|Name=32|Designator=A-32|PinPropagationDelay=0.000000E+000
|RECORD=2|OwnerIndex=1698|OwnerPartId=1|FormalType=1|PinConglomerate=58|PinLength=30|Location.X=490|Location.Y=338|Name=33|Designator=A-33|PinPropagationDelay=0.000000E+000
|RECORD=2|OwnerIndex=1698|OwnerPartId=1|FormalType=1|PinConglomerate=56|PinLength=30|Location.X=550|Location.Y=338|Name=34|Designator=A-34|PinPropagationDelay=0.000000E+000
|RECORD=2|OwnerIndex=1698|OwnerPartId=1|FormalType=1|PinConglomerate=58|PinLength=30|Location.X=490|Location.Y=328|Name=35|Designator=A-35|PinPropagationDelay=0.000000E+000
|RECORD=2|OwnerIndex=1698|OwnerPartId=1|FormalType=1|PinConglomerate=56|PinLength=30|Location.X=550|Location.Y=328|Name=36|Designator=A-36|PinPropagationDelay=0.000000E+000
|RECORD=2|OwnerIndex=1698|OwnerPartId=1|FormalType=1|PinConglomerate=58|PinLength=30|Location.X=490|Location.Y=318|Name=37|Designator=A-37|PinPropagationDelay=0.000000E+000
|RECORD=2|OwnerIndex=1698|OwnerPartId=1|FormalType=1|PinConglomerate=56|PinLength=30|Location.X=550|Location.Y=318|Name=38|Designator=A-38|PinPropagationDelay=0.000000E+000
|RECORD=2|OwnerIndex=1698|OwnerPartId=1|FormalType=1|PinConglomerate=58|PinLength=30|Location.X=490|Location.Y=308|Name=39|Designator=A-39|PinPropagationDelay=0.000000E+000
|RECORD=2|OwnerIndex=1698|OwnerPartId=1|FormalType=1|PinConglomerate=56|PinLength=30|Location.X=550|Location.Y=308|Name=40|Designator=A-40|PinPropagationDelay=0.000000E+000
|RECORD=2|OwnerIndex=1698|OwnerPartId=1|FormalType=1|PinConglomerate=58|PinLength=30|Location.X=490|Location.Y=298|Name=41|Designator=A-41|PinPropagationDelay=0.000000E+000
|RECORD=2|OwnerIndex=1698|OwnerPartId=1|FormalType=1|PinConglomerate=56|PinLength=30|Location.X=550|Location.Y=298|Name=42|Designator=A-42|PinPropagationDelay=0.000000E+000
|RECORD=2|OwnerIndex=1698|OwnerPartId=1|FormalType=1|PinConglomerate=58|PinLength=30|Location.X=490|Location.Y=288|Name=43|Designator=A-43|PinPropagationDelay=0.000000E+000
|RECORD=2|OwnerIndex=1698|OwnerPartId=1|FormalType=1|PinConglomerate=56|PinLength=30|Location.X=550|Location.Y=288|Name=44|Designator=A-44|PinPropagationDelay=0.000000E+000
|RECORD=2|OwnerIndex=1698|OwnerPartId=1|FormalType=1|PinConglomerate=58|PinLength=30|Location.X=490|Location.Y=278|Name=45|Designator=A-45|PinPropagationDelay=0.000000E+000
|RECORD=2|OwnerIndex=1698|OwnerPartId=1|FormalType=1|PinConglomerate=56|PinLength=30|Location.X=550|Location.Y=278|Name=46|Designator=A-46|PinPropagationDelay=0.000000E+000
|RECORD=2|OwnerIndex=1698|OwnerPartId=1|FormalType=1|PinConglomerate=58|PinLength=30|Location.X=490|Location.Y=268|Name=47|Designator=A-47|PinPropagationDelay=0.000000E+000
|RECORD=2|OwnerIndex=1698|OwnerPartId=1|FormalType=1|PinConglomerate=56|PinLength=30|Location.X=550|Location.Y=268|Name=48|Designator=A-48|PinPropagationDelay=0.000000E+000
|RECORD=2|OwnerIndex=1698|OwnerPartId=1|FormalType=1|PinConglomerate=58|PinLength=30|Location.X=490|Location.Y=258|Name=49|Designator=A-49|PinPropagationDelay=0.000000E+000
|RECORD=2|OwnerIndex=1698|OwnerPartId=1|FormalType=1|PinConglomerate=56|PinLength=30|Location.X=550|Location.Y=258|Name=50|Designator=A-50|PinPropagationDelay=0.000000E+000
|RECORD=2|OwnerIndex=1698|OwnerPartId=1|FormalType=1|PinConglomerate=58|PinLength=30|Location.X=490|Location.Y=248|Name=51|Designator=A-51|PinPropagationDelay=0.000000E+000
|RECORD=2|OwnerIndex=1698|OwnerPartId=1|FormalType=1|PinConglomerate=56|PinLength=30|Location.X=550|Location.Y=248|Name=52|Designator=A-52|PinPropagationDelay=0.000000E+000
|RECORD=2|OwnerIndex=1698|OwnerPartId=1|FormalType=1|PinConglomerate=58|PinLength=30|Location.X=490|Location.Y=238|Name=53|Designator=A-53|PinPropagationDelay=0.000000E+000
|RECORD=2|OwnerIndex=1698|OwnerPartId=1|FormalType=1|PinConglomerate=56|PinLength=30|Location.X=550|Location.Y=238|Name=54|Designator=A-54|PinPropagationDelay=0.000000E+000
|RECORD=2|OwnerIndex=1698|OwnerPartId=1|FormalType=1|PinConglomerate=58|PinLength=30|Location.X=490|Location.Y=228|Name=55|Designator=A-55|PinPropagationDelay=0.000000E+000
|RECORD=2|OwnerIndex=1698|OwnerPartId=1|FormalType=1|PinConglomerate=56|PinLength=30|Location.X=550|Location.Y=228|Name=56|Designator=A-56|PinPropagationDelay=0.000000E+000
|RECORD=2|OwnerIndex=1698|OwnerPartId=1|FormalType=1|PinConglomerate=58|PinLength=30|Location.X=490|Location.Y=218|Name=57|Designator=A-57|PinPropagationDelay=0.000000E+000
|RECORD=2|OwnerIndex=1698|OwnerPartId=1|FormalType=1|PinConglomerate=56|PinLength=30|Location.X=550|Location.Y=218|Name=58|Designator=A-58|PinPropagationDelay=0.000000E+000
|RECORD=2|OwnerIndex=1698|OwnerPartId=1|FormalType=1|PinConglomerate=58|PinLength=30|Location.X=490|Location.Y=208|Name=59|Designator=A-59|PinPropagationDelay=0.000000E+000
|RECORD=2|OwnerIndex=1698|OwnerPartId=1|FormalType=1|PinConglomerate=56|PinLength=30|Location.X=550|Location.Y=208|Name=60|Designator=A-60|PinPropagationDelay=0.000000E+000
|RECORD=2|OwnerIndex=1698|OwnerPartId=1|FormalType=1|PinConglomerate=58|PinLength=30|Location.X=490|Location.Y=198|Name=61|Designator=A-61|PinPropagationDelay=0.000000E+000
|RECORD=2|OwnerIndex=1698|OwnerPartId=1|FormalType=1|PinConglomerate=56|PinLength=30|Location.X=550|Location.Y=198|Name=62|Designator=A-62|PinPropagationDelay=0.000000E+000
|RECORD=2|OwnerIndex=1698|OwnerPartId=1|FormalType=1|PinConglomerate=58|PinLength=30|Location.X=490|Location.Y=188|Name=63|Designator=A-63|PinPropagationDelay=0.000000E+000
|RECORD=2|OwnerIndex=1698|OwnerPartId=1|FormalType=1|PinConglomerate=56|PinLength=30|Location.X=550|Location.Y=188|Name=64|Designator=A-64|PinPropagationDelay=0.000000E+000
|RECORD=2|OwnerIndex=1698|OwnerPartId=1|FormalType=1|PinConglomerate=58|PinLength=30|Location.X=490|Location.Y=178|Name=65|Designator=A-65|PinPropagationDelay=0.000000E+000
|RECORD=2|OwnerIndex=1698|OwnerPartId=1|FormalType=1|PinConglomerate=56|PinLength=30|Location.X=550|Location.Y=178|Name=66|Designator=A-66|PinPropagationDelay=0.000000E+000
|RECORD=2|OwnerIndex=1698|OwnerPartId=1|FormalType=1|PinConglomerate=58|PinLength=30|Location.X=490|Location.Y=168|Name=67|Designator=A-67|PinPropagationDelay=0.000000E+000
|RECORD=2|OwnerIndex=1698|OwnerPartId=1|FormalType=1|PinConglomerate=56|PinLength=30|Location.X=550|Location.Y=168|Name=68|Designator=A-68|PinPropagationDelay=0.000000E+000
|RECORD=2|OwnerIndex=1698|OwnerPartId=1|FormalType=1|PinConglomerate=58|PinLength=30|Location.X=490|Location.Y=158|Name=69|Designator=A-69|PinPropagationDelay=0.000000E+000
|RECORD=2|OwnerIndex=1698|OwnerPartId=1|FormalType=1|PinConglomerate=56|PinLength=30|Location.X=550|Location.Y=158|Name=70|Designator=A-70|PinPropagationDelay=0.000000E+000
|RECORD=2|OwnerIndex=1698|OwnerPartId=1|FormalType=1|PinConglomerate=58|PinLength=30|Location.X=490|Location.Y=148|Name=71|Designator=A-71|PinPropagationDelay=0.000000E+000
|RECORD=2|OwnerIndex=1698|OwnerPartId=1|FormalType=1|PinConglomerate=56|PinLength=30|Location.X=550|Location.Y=148|Name=72|Designator=A-72|PinPropagationDelay=0.000000E+000
|RECORD=2|OwnerIndex=1698|OwnerPartId=1|FormalType=1|PinConglomerate=58|PinLength=30|Location.X=490|Location.Y=138|Name=73|Designator=A-73|PinPropagationDelay=0.000000E+000
|RECORD=2|OwnerIndex=1698|OwnerPartId=1|FormalType=1|PinConglomerate=56|PinLength=30|Location.X=550|Location.Y=138|Name=74|Designator=A-74|PinPropagationDelay=0.000000E+000
|RECORD=2|OwnerIndex=1698|OwnerPartId=1|FormalType=1|PinConglomerate=58|PinLength=30|Location.X=490|Location.Y=128|Name=75|Designator=A-75|PinPropagationDelay=0.000000E+000
|RECORD=2|OwnerIndex=1698|OwnerPartId=1|FormalType=1|PinConglomerate=56|PinLength=30|Location.X=550|Location.Y=128|Name=76|Designator=A-76|PinPropagationDelay=0.000000E+000
|RECORD=2|OwnerIndex=1698|OwnerPartId=1|FormalType=1|PinConglomerate=58|PinLength=30|Location.X=490|Location.Y=118|Name=77|Designator=A-77|PinPropagationDelay=0.000000E+000
|RECORD=2|OwnerIndex=1698|OwnerPartId=1|FormalType=1|PinConglomerate=56|PinLength=30|Location.X=550|Location.Y=118|Name=78|Designator=A-78|PinPropagationDelay=0.000000E+000
|RECORD=2|OwnerIndex=1698|OwnerPartId=1|FormalType=1|PinConglomerate=58|PinLength=30|Location.X=490|Location.Y=108|Name=79|Designator=A-79|PinPropagationDelay=0.000000E+000
|RECORD=2|OwnerIndex=1698|OwnerPartId=1|FormalType=1|PinConglomerate=56|PinLength=30|Location.X=550|Location.Y=108|Name=80|Designator=A-80|PinPropagationDelay=0.000000E+000
|RECORD=2|OwnerIndex=1698|OwnerPartId=1|FormalType=1|PinConglomerate=58|PinLength=30|Location.X=490|Location.Y=98|Name=81|Designator=A-81|PinPropagationDelay=0.000000E+000
|RECORD=2|OwnerIndex=1698|OwnerPartId=1|FormalType=1|PinConglomerate=56|PinLength=30|Location.X=550|Location.Y=98|Name=82|Designator=A-82|PinPropagationDelay=0.000000E+000
|RECORD=2|OwnerIndex=1698|OwnerPartId=1|FormalType=1|PinConglomerate=58|PinLength=30|Location.X=490|Location.Y=88|Name=83|Designator=A-83|PinPropagationDelay=0.000000E+000
|RECORD=2|OwnerIndex=1698|OwnerPartId=1|FormalType=1|PinConglomerate=56|PinLength=30|Location.X=550|Location.Y=88|Name=84|Designator=A-84|PinPropagationDelay=0.000000E+000
|RECORD=34|OwnerIndex=1698|IndexInSheet=-1|OwnerPartId=-1|Location.X=490|Location.Y=508|Color=8388608|FontID=1|Text=P1|Name=Designator|ReadOnlyState=1
|RECORD=41|OwnerIndex=1698|IndexInSheet=-1|OwnerPartId=-1|Location.X=490|Location.Y=68|Color=8388608|FontID=1|Text=FPGA_CONN|Name=Comment
|RECORD=44|OwnerIndex=1698
|RECORD=45|OwnerIndex=2377|IndexInSheet=-1|ModelName=FPGA_CONN|ModelType=PCBLIB|DatafileCount=1|ModelDatafileEntity0=FPGA_CONN|ModelDatafileKind0=PCBLib|IsCurrent=T
|RECORD=46|OwnerIndex=2378
|RECORD=48|OwnerIndex=2378
|RECORD=1|LibReference=FPGA_CONN|PartCount=5|DisplayModeCount=1|IndexInSheet=306|OwnerPartId=-1|Location.X=1160|Location.Y=498|CurrentPartId=4|LibraryPath=*|SourceLibraryName=FPGA_CONN.SchLib|TargetFileName=*|AreaColor=11599871|Color=128|PartIDLocked=T|NotUseDBTableName=T|DesignItemId=FPGA_CONN|AllPinCount=336
|RECORD=14|OwnerIndex=2381|IsNotAccesible=T|OwnerPartId=2|Location.X=1190|Location.Y=78|Corner.X=1250|Corner.Y=508|Color=128|AreaColor=11599871|IsSolid=T
|RECORD=2|OwnerIndex=2381|OwnerPartId=2|FormalType=1|PinConglomerate=58|PinLength=30|Location.X=1190|Location.Y=498|Name=1|Designator=B-1|PinPropagationDelay=0.000000E+000
|RECORD=2|OwnerIndex=2381|OwnerPartId=2|FormalType=1|PinConglomerate=56|PinLength=30|Location.X=1250|Location.Y=498|Name=2|Designator=B-2|PinPropagationDelay=0.000000E+000
|RECORD=2|OwnerIndex=2381|OwnerPartId=2|FormalType=1|PinConglomerate=58|PinLength=30|Location.X=1190|Location.Y=488|Name=3|Designator=B-3|PinPropagationDelay=0.000000E+000
|RECORD=2|OwnerIndex=2381|OwnerPartId=2|FormalType=1|PinConglomerate=56|PinLength=30|Location.X=1250|Location.Y=488|Name=4|Designator=B-4|PinPropagationDelay=0.000000E+000
|RECORD=2|OwnerIndex=2381|OwnerPartId=2|FormalType=1|PinConglomerate=58|PinLength=30|Location.X=1190|Location.Y=478|Name=5|Designator=B-5|PinPropagationDelay=0.000000E+000
|RECORD=2|OwnerIndex=2381|OwnerPartId=2|FormalType=1|PinConglomerate=56|PinLength=30|Location.X=1250|Location.Y=478|Name=6|Designator=B-6|PinPropagationDelay=0.000000E+000
|RECORD=2|OwnerIndex=2381|OwnerPartId=2|FormalType=1|PinConglomerate=58|PinLength=30|Location.X=1190|Location.Y=468|Name=7|Designator=B-7|PinPropagationDelay=0.000000E+000
|RECORD=2|OwnerIndex=2381|OwnerPartId=2|FormalType=1|PinConglomerate=56|PinLength=30|Location.X=1250|Location.Y=468|Name=8|Designator=B-8|PinPropagationDelay=0.000000E+000
|RECORD=2|OwnerIndex=2381|OwnerPartId=2|FormalType=1|PinConglomerate=58|PinLength=30|Location.X=1190|Location.Y=458|Name=9|Designator=B-9|PinPropagationDelay=0.000000E+000
|RECORD=2|OwnerIndex=2381|OwnerPartId=2|FormalType=1|PinConglomerate=56|PinLength=30|Location.X=1250|Location.Y=458|Name=10|Designator=B-10|PinPropagationDelay=0.000000E+000
|RECORD=2|OwnerIndex=2381|OwnerPartId=2|FormalType=1|PinConglomerate=58|PinLength=30|Location.X=1190|Location.Y=448|Name=11|Designator=B-11|PinPropagationDelay=0.000000E+000
|RECORD=2|OwnerIndex=2381|OwnerPartId=2|FormalType=1|PinConglomerate=56|PinLength=30|Location.X=1250|Location.Y=448|Name=12|Designator=B-12|PinPropagationDelay=0.000000E+000
|RECORD=2|OwnerIndex=2381|OwnerPartId=2|FormalType=1|PinConglomerate=58|PinLength=30|Location.X=1190|Location.Y=438|Name=13|Designator=B-13|PinPropagationDelay=0.000000E+000
|RECORD=2|OwnerIndex=2381|OwnerPartId=2|FormalType=1|PinConglomerate=56|PinLength=30|Location.X=1250|Location.Y=438|Name=14|Designator=B-14|PinPropagationDelay=0.000000E+000
|RECORD=2|OwnerIndex=2381|OwnerPartId=2|FormalType=1|PinConglomerate=58|PinLength=30|Location.X=1190|Location.Y=428|Name=15|Designator=B-15|PinPropagationDelay=0.000000E+000
|RECORD=2|OwnerIndex=2381|OwnerPartId=2|FormalType=1|PinConglomerate=56|PinLength=30|Location.X=1250|Location.Y=428|Name=16|Designator=B-16|PinPropagationDelay=0.000000E+000
|RECORD=2|OwnerIndex=2381|OwnerPartId=2|FormalType=1|PinConglomerate=58|PinLength=30|Location.X=1190|Location.Y=418|Name=17|Designator=B-17|PinPropagationDelay=0.000000E+000
|RECORD=2|OwnerIndex=2381|OwnerPartId=2|FormalType=1|PinConglomerate=56|PinLength=30|Location.X=1250|Location.Y=418|Name=18|Designator=B-18|PinPropagationDelay=0.000000E+000
|RECORD=2|OwnerIndex=2381|OwnerPartId=2|FormalType=1|PinConglomerate=58|PinLength=30|Location.X=1190|Location.Y=408|Name=19|Designator=B-19|PinPropagationDelay=0.000000E+000
|RECORD=2|OwnerIndex=2381|OwnerPartId=2|FormalType=1|PinConglomerate=56|PinLength=30|Location.X=1250|Location.Y=408|Name=20|Designator=B-20|PinPropagationDelay=0.000000E+000
|RECORD=2|OwnerIndex=2381|OwnerPartId=2|FormalType=1|PinConglomerate=58|PinLength=30|Location.X=1190|Location.Y=398|Name=21|Designator=B-21|PinPropagationDelay=0.000000E+000
|RECORD=2|OwnerIndex=2381|OwnerPartId=2|FormalType=1|PinConglomerate=56|PinLength=30|Location.X=1250|Location.Y=398|Name=22|Designator=B-22|PinPropagationDelay=0.000000E+000
|RECORD=2|OwnerIndex=2381|OwnerPartId=2|FormalType=1|PinConglomerate=58|PinLength=30|Location.X=1190|Location.Y=388|Name=23|Designator=B-23|PinPropagationDelay=0.000000E+000
|RECORD=2|OwnerIndex=2381|OwnerPartId=2|FormalType=1|PinConglomerate=56|PinLength=30|Location.X=1250|Location.Y=388|Name=24|Designator=B-24|PinPropagationDelay=0.000000E+000
|RECORD=2|OwnerIndex=2381|OwnerPartId=2|FormalType=1|PinConglomerate=58|PinLength=30|Location.X=1190|Location.Y=378|Name=25|Designator=B-25|PinPropagationDelay=0.000000E+000
|RECORD=2|OwnerIndex=2381|OwnerPartId=2|FormalType=1|PinConglomerate=56|PinLength=30|Location.X=1250|Location.Y=378|Name=26|Designator=B-26|PinPropagationDelay=0.000000E+000
|RECORD=2|OwnerIndex=2381|OwnerPartId=2|FormalType=1|PinConglomerate=58|PinLength=30|Location.X=1190|Location.Y=368|Name=27|Designator=B-27|PinPropagationDelay=0.000000E+000
|RECORD=2|OwnerIndex=2381|OwnerPartId=2|FormalType=1|PinConglomerate=56|PinLength=30|Location.X=1250|Location.Y=368|Name=28|Designator=B-28|PinPropagationDelay=0.000000E+000
|RECORD=2|OwnerIndex=2381|OwnerPartId=2|FormalType=1|PinConglomerate=58|PinLength=30|Location.X=1190|Location.Y=358|Name=29|Designator=B-29|PinPropagationDelay=0.000000E+000
|RECORD=2|OwnerIndex=2381|OwnerPartId=2|FormalType=1|PinConglomerate=56|PinLength=30|Location.X=1250|Location.Y=358|Name=30|Designator=B-30|PinPropagationDelay=0.000000E+000
|RECORD=2|OwnerIndex=2381|OwnerPartId=2|FormalType=1|PinConglomerate=58|PinLength=30|Location.X=1190|Location.Y=348|Name=31|Designator=B-31|PinPropagationDelay=0.000000E+000
|RECORD=2|OwnerIndex=2381|OwnerPartId=2|FormalType=1|PinConglomerate=56|PinLength=30|Location.X=1250|Location.Y=348|Name=32|Designator=B-32|PinPropagationDelay=0.000000E+000
|RECORD=2|OwnerIndex=2381|OwnerPartId=2|FormalType=1|PinConglomerate=58|PinLength=30|Location.X=1190|Location.Y=338|Name=33|Designator=B-33|PinPropagationDelay=0.000000E+000
|RECORD=2|OwnerIndex=2381|OwnerPartId=2|FormalType=1|PinConglomerate=56|PinLength=30|Location.X=1250|Location.Y=338|Name=34|Designator=B-34|PinPropagationDelay=0.000000E+000
|RECORD=2|OwnerIndex=2381|OwnerPartId=2|FormalType=1|PinConglomerate=58|PinLength=30|Location.X=1190|Location.Y=328|Name=35|Designator=B-35|PinPropagationDelay=0.000000E+000
|RECORD=2|OwnerIndex=2381|OwnerPartId=2|FormalType=1|PinConglomerate=56|PinLength=30|Location.X=1250|Location.Y=328|Name=36|Designator=B-36|PinPropagationDelay=0.000000E+000
|RECORD=2|OwnerIndex=2381|OwnerPartId=2|FormalType=1|PinConglomerate=58|PinLength=30|Location.X=1190|Location.Y=318|Name=37|Designator=B-37|PinPropagationDelay=0.000000E+000
|RECORD=2|OwnerIndex=2381|OwnerPartId=2|FormalType=1|PinConglomerate=56|PinLength=30|Location.X=1250|Location.Y=318|Name=38|Designator=B-38|PinPropagationDelay=0.000000E+000
|RECORD=2|OwnerIndex=2381|OwnerPartId=2|FormalType=1|PinConglomerate=58|PinLength=30|Location.X=1190|Location.Y=308|Name=39|Designator=B-39|PinPropagationDelay=0.000000E+000
|RECORD=2|OwnerIndex=2381|OwnerPartId=2|FormalType=1|PinConglomerate=56|PinLength=30|Location.X=1250|Location.Y=308|Name=40|Designator=B-40|PinPropagationDelay=0.000000E+000
|RECORD=2|OwnerIndex=2381|OwnerPartId=2|FormalType=1|PinConglomerate=58|PinLength=30|Location.X=1190|Location.Y=298|Name=41|Designator=B-41|PinPropagationDelay=0.000000E+000
|RECORD=2|OwnerIndex=2381|OwnerPartId=2|FormalType=1|PinConglomerate=56|PinLength=30|Location.X=1250|Location.Y=298|Name=42|Designator=B-42|PinPropagationDelay=0.000000E+000
|RECORD=2|OwnerIndex=2381|OwnerPartId=2|FormalType=1|PinConglomerate=58|PinLength=30|Location.X=1190|Location.Y=288|Name=43|Designator=B-43|PinPropagationDelay=0.000000E+000
|RECORD=2|OwnerIndex=2381|OwnerPartId=2|FormalType=1|PinConglomerate=56|PinLength=30|Location.X=1250|Location.Y=288|Name=44|Designator=B-44|PinPropagationDelay=0.000000E+000
|RECORD=2|OwnerIndex=2381|OwnerPartId=2|FormalType=1|PinConglomerate=58|PinLength=30|Location.X=1190|Location.Y=278|Name=45|Designator=B-45|PinPropagationDelay=0.000000E+000
|RECORD=2|OwnerIndex=2381|OwnerPartId=2|FormalType=1|PinConglomerate=56|PinLength=30|Location.X=1250|Location.Y=278|Name=46|Designator=B-46|PinPropagationDelay=0.000000E+000
|RECORD=2|OwnerIndex=2381|OwnerPartId=2|FormalType=1|PinConglomerate=58|PinLength=30|Location.X=1190|Location.Y=268|Name=47|Designator=B-47|PinPropagationDelay=0.000000E+000
|RECORD=2|OwnerIndex=2381|OwnerPartId=2|FormalType=1|PinConglomerate=56|PinLength=30|Location.X=1250|Location.Y=268|Name=48|Designator=B-48|PinPropagationDelay=0.000000E+000
|RECORD=2|OwnerIndex=2381|OwnerPartId=2|FormalType=1|PinConglomerate=58|PinLength=30|Location.X=1190|Location.Y=258|Name=49|Designator=B-49|PinPropagationDelay=0.000000E+000
|RECORD=2|OwnerIndex=2381|OwnerPartId=2|FormalType=1|PinConglomerate=56|PinLength=30|Location.X=1250|Location.Y=258|Name=50|Designator=B-50|PinPropagationDelay=0.000000E+000
|RECORD=2|OwnerIndex=2381|OwnerPartId=2|FormalType=1|PinConglomerate=58|PinLength=30|Location.X=1190|Location.Y=248|Name=51|Designator=B-51|PinPropagationDelay=0.000000E+000
|RECORD=2|OwnerIndex=2381|OwnerPartId=2|FormalType=1|PinConglomerate=56|PinLength=30|Location.X=1250|Location.Y=248|Name=52|Designator=B-52|PinPropagationDelay=0.000000E+000
|RECORD=2|OwnerIndex=2381|OwnerPartId=2|FormalType=1|PinConglomerate=58|PinLength=30|Location.X=1190|Location.Y=238|Name=53|Designator=B-53|PinPropagationDelay=0.000000E+000
|RECORD=2|OwnerIndex=2381|OwnerPartId=2|FormalType=1|PinConglomerate=56|PinLength=30|Location.X=1250|Location.Y=238|Name=54|Designator=B-54|PinPropagationDelay=0.000000E+000
|RECORD=2|OwnerIndex=2381|OwnerPartId=2|FormalType=1|PinConglomerate=58|PinLength=30|Location.X=1190|Location.Y=228|Name=55|Designator=B-55|PinPropagationDelay=0.000000E+000
|RECORD=2|OwnerIndex=2381|OwnerPartId=2|FormalType=1|PinConglomerate=56|PinLength=30|Location.X=1250|Location.Y=228|Name=56|Designator=B-56|PinPropagationDelay=0.000000E+000
|RECORD=2|OwnerIndex=2381|OwnerPartId=2|FormalType=1|PinConglomerate=58|PinLength=30|Location.X=1190|Location.Y=218|Name=57|Designator=B-57|PinPropagationDelay=0.000000E+000
|RECORD=2|OwnerIndex=2381|OwnerPartId=2|FormalType=1|PinConglomerate=56|PinLength=30|Location.X=1250|Location.Y=218|Name=58|Designator=B-58|PinPropagationDelay=0.000000E+000
|RECORD=2|OwnerIndex=2381|OwnerPartId=2|FormalType=1|PinConglomerate=58|PinLength=30|Location.X=1190|Location.Y=208|Name=59|Designator=B-59|PinPropagationDelay=0.000000E+000
|RECORD=2|OwnerIndex=2381|OwnerPartId=2|FormalType=1|PinConglomerate=56|PinLength=30|Location.X=1250|Location.Y=208|Name=60|Designator=B-60|PinPropagationDelay=0.000000E+000
|RECORD=2|OwnerIndex=2381|OwnerPartId=2|FormalType=1|PinConglomerate=58|PinLength=30|Location.X=1190|Location.Y=198|Name=61|Designator=B-61|PinPropagationDelay=0.000000E+000
|RECORD=2|OwnerIndex=2381|OwnerPartId=2|FormalType=1|PinConglomerate=56|PinLength=30|Location.X=1250|Location.Y=198|Name=62|Designator=B-62|PinPropagationDelay=0.000000E+000
|RECORD=2|OwnerIndex=2381|OwnerPartId=2|FormalType=1|PinConglomerate=58|PinLength=30|Location.X=1190|Location.Y=188|Name=63|Designator=B-63|PinPropagationDelay=0.000000E+000
|RECORD=2|OwnerIndex=2381|OwnerPartId=2|FormalType=1|PinConglomerate=56|PinLength=30|Location.X=1250|Location.Y=188|Name=64|Designator=B-64|PinPropagationDelay=0.000000E+000
|RECORD=2|OwnerIndex=2381|OwnerPartId=2|FormalType=1|PinConglomerate=58|PinLength=30|Location.X=1190|Location.Y=178|Name=65|Designator=B-65|PinPropagationDelay=0.000000E+000
|RECORD=2|OwnerIndex=2381|OwnerPartId=2|FormalType=1|PinConglomerate=56|PinLength=30|Location.X=1250|Location.Y=178|Name=66|Designator=B-66|PinPropagationDelay=0.000000E+000
|RECORD=2|OwnerIndex=2381|OwnerPartId=2|FormalType=1|PinConglomerate=58|PinLength=30|Location.X=1190|Location.Y=168|Name=67|Designator=B-67|PinPropagationDelay=0.000000E+000
|RECORD=2|OwnerIndex=2381|OwnerPartId=2|FormalType=1|PinConglomerate=56|PinLength=30|Location.X=1250|Location.Y=168|Name=68|Designator=B-68|PinPropagationDelay=0.000000E+000
|RECORD=2|OwnerIndex=2381|OwnerPartId=2|FormalType=1|PinConglomerate=58|PinLength=30|Location.X=1190|Location.Y=158|Name=69|Designator=B-69|PinPropagationDelay=0.000000E+000
|RECORD=2|OwnerIndex=2381|OwnerPartId=2|FormalType=1|PinConglomerate=56|PinLength=30|Location.X=1250|Location.Y=158|Name=70|Designator=B-70|PinPropagationDelay=0.000000E+000
|RECORD=2|OwnerIndex=2381|OwnerPartId=2|FormalType=1|PinConglomerate=58|PinLength=30|Location.X=1190|Location.Y=148|Name=71|Designator=B-71|PinPropagationDelay=0.000000E+000
|RECORD=2|OwnerIndex=2381|OwnerPartId=2|FormalType=1|PinConglomerate=56|PinLength=30|Location.X=1250|Location.Y=148|Name=72|Designator=B-72|PinPropagationDelay=0.000000E+000
|RECORD=2|OwnerIndex=2381|OwnerPartId=2|FormalType=1|PinConglomerate=58|PinLength=30|Location.X=1190|Location.Y=138|Name=73|Designator=B-73|PinPropagationDelay=0.000000E+000
|RECORD=2|OwnerIndex=2381|OwnerPartId=2|FormalType=1|PinConglomerate=56|PinLength=30|Location.X=1250|Location.Y=138|Name=74|Designator=B-74|PinPropagationDelay=0.000000E+000
|RECORD=2|OwnerIndex=2381|OwnerPartId=2|FormalType=1|PinConglomerate=58|PinLength=30|Location.X=1190|Location.Y=128|Name=75|Designator=B-75|PinPropagationDelay=0.000000E+000
|RECORD=2|OwnerIndex=2381|OwnerPartId=2|FormalType=1|PinConglomerate=56|PinLength=30|Location.X=1250|Location.Y=128|Name=76|Designator=B-76|PinPropagationDelay=0.000000E+000
|RECORD=2|OwnerIndex=2381|OwnerPartId=2|FormalType=1|PinConglomerate=58|PinLength=30|Location.X=1190|Location.Y=118|Name=77|Designator=B-77|PinPropagationDelay=0.000000E+000
|RECORD=2|OwnerIndex=2381|OwnerPartId=2|FormalType=1|PinConglomerate=56|PinLength=30|Location.X=1250|Location.Y=118|Name=78|Designator=B-78|PinPropagationDelay=0.000000E+000
|RECORD=2|OwnerIndex=2381|OwnerPartId=2|FormalType=1|PinConglomerate=58|PinLength=30|Location.X=1190|Location.Y=108|Name=79|Designator=B-79|PinPropagationDelay=0.000000E+000
|RECORD=2|OwnerIndex=2381|OwnerPartId=2|FormalType=1|PinConglomerate=56|PinLength=30|Location.X=1250|Location.Y=108|Name=80|Designator=B-80|PinPropagationDelay=0.000000E+000
|RECORD=2|OwnerIndex=2381|OwnerPartId=2|FormalType=1|PinConglomerate=58|PinLength=30|Location.X=1190|Location.Y=98|Name=81|Designator=B-81|PinPropagationDelay=0.000000E+000
|RECORD=2|OwnerIndex=2381|OwnerPartId=2|FormalType=1|PinConglomerate=56|PinLength=30|Location.X=1250|Location.Y=98|Name=82|Designator=B-82|PinPropagationDelay=0.000000E+000
|RECORD=2|OwnerIndex=2381|OwnerPartId=2|FormalType=1|PinConglomerate=58|PinLength=30|Location.X=1190|Location.Y=88|Name=83|Designator=B-83|PinPropagationDelay=0.000000E+000
|RECORD=2|OwnerIndex=2381|OwnerPartId=2|FormalType=1|PinConglomerate=56|PinLength=30|Location.X=1250|Location.Y=88|Name=84|Designator=B-84|PinPropagationDelay=0.000000E+000
|RECORD=14|OwnerIndex=2381|IsNotAccesible=T|IndexInSheet=85|OwnerPartId=3|Location.X=1190|Location.Y=78|Corner.X=1250|Corner.Y=508|Color=128|AreaColor=11599871|IsSolid=T
|RECORD=2|OwnerIndex=2381|OwnerPartId=3|FormalType=1|PinConglomerate=58|PinLength=30|Location.X=1190|Location.Y=498|Name=1|Designator=C-1|PinPropagationDelay=0.000000E+000
|RECORD=2|OwnerIndex=2381|OwnerPartId=3|FormalType=1|PinConglomerate=56|PinLength=30|Location.X=1250|Location.Y=498|Name=2|Designator=C-2|PinPropagationDelay=0.000000E+000
|RECORD=2|OwnerIndex=2381|OwnerPartId=3|FormalType=1|PinConglomerate=58|PinLength=30|Location.X=1190|Location.Y=488|Name=3|Designator=C-3|PinPropagationDelay=0.000000E+000
|RECORD=2|OwnerIndex=2381|OwnerPartId=3|FormalType=1|PinConglomerate=56|PinLength=30|Location.X=1250|Location.Y=488|Name=4|Designator=C-4|PinPropagationDelay=0.000000E+000
|RECORD=2|OwnerIndex=2381|OwnerPartId=3|FormalType=1|PinConglomerate=58|PinLength=30|Location.X=1190|Location.Y=478|Name=5|Designator=C-5|PinPropagationDelay=0.000000E+000
|RECORD=2|OwnerIndex=2381|OwnerPartId=3|FormalType=1|PinConglomerate=56|PinLength=30|Location.X=1250|Location.Y=478|Name=6|Designator=C-6|PinPropagationDelay=0.000000E+000
|RECORD=2|OwnerIndex=2381|OwnerPartId=3|FormalType=1|PinConglomerate=58|PinLength=30|Location.X=1190|Location.Y=468|Name=7|Designator=C-7|PinPropagationDelay=0.000000E+000
|RECORD=2|OwnerIndex=2381|OwnerPartId=3|FormalType=1|PinConglomerate=56|PinLength=30|Location.X=1250|Location.Y=468|Name=8|Designator=C-8|PinPropagationDelay=0.000000E+000
|RECORD=2|OwnerIndex=2381|OwnerPartId=3|FormalType=1|PinConglomerate=58|PinLength=30|Location.X=1190|Location.Y=458|Name=9|Designator=C-9|PinPropagationDelay=0.000000E+000
|RECORD=2|OwnerIndex=2381|OwnerPartId=3|FormalType=1|PinConglomerate=56|PinLength=30|Location.X=1250|Location.Y=458|Name=10|Designator=C-10|PinPropagationDelay=0.000000E+000
|RECORD=2|OwnerIndex=2381|OwnerPartId=3|FormalType=1|PinConglomerate=58|PinLength=30|Location.X=1190|Location.Y=448|Name=11|Designator=C-11|PinPropagationDelay=0.000000E+000
|RECORD=2|OwnerIndex=2381|OwnerPartId=3|FormalType=1|PinConglomerate=56|PinLength=30|Location.X=1250|Location.Y=448|Name=12|Designator=C-12|PinPropagationDelay=0.000000E+000
|RECORD=2|OwnerIndex=2381|OwnerPartId=3|FormalType=1|PinConglomerate=58|PinLength=30|Location.X=1190|Location.Y=438|Name=13|Designator=C-13|PinPropagationDelay=0.000000E+000
|RECORD=2|OwnerIndex=2381|OwnerPartId=3|FormalType=1|PinConglomerate=56|PinLength=30|Location.X=1250|Location.Y=438|Name=14|Designator=C-14|PinPropagationDelay=0.000000E+000
|RECORD=2|OwnerIndex=2381|OwnerPartId=3|FormalType=1|PinConglomerate=58|PinLength=30|Location.X=1190|Location.Y=428|Name=15|Designator=C-15|PinPropagationDelay=0.000000E+000
|RECORD=2|OwnerIndex=2381|OwnerPartId=3|FormalType=1|PinConglomerate=56|PinLength=30|Location.X=1250|Location.Y=428|Name=16|Designator=C-16|PinPropagationDelay=0.000000E+000
|RECORD=2|OwnerIndex=2381|OwnerPartId=3|FormalType=1|PinConglomerate=58|PinLength=30|Location.X=1190|Location.Y=418|Name=17|Designator=C-17|PinPropagationDelay=0.000000E+000
|RECORD=2|OwnerIndex=2381|OwnerPartId=3|FormalType=1|PinConglomerate=56|PinLength=30|Location.X=1250|Location.Y=418|Name=18|Designator=C-18|PinPropagationDelay=0.000000E+000
|RECORD=2|OwnerIndex=2381|OwnerPartId=3|FormalType=1|PinConglomerate=58|PinLength=30|Location.X=1190|Location.Y=408|Name=19|Designator=C-19|PinPropagationDelay=0.000000E+000
|RECORD=2|OwnerIndex=2381|OwnerPartId=3|FormalType=1|PinConglomerate=56|PinLength=30|Location.X=1250|Location.Y=408|Name=20|Designator=C-20|PinPropagationDelay=0.000000E+000
|RECORD=2|OwnerIndex=2381|OwnerPartId=3|FormalType=1|PinConglomerate=58|PinLength=30|Location.X=1190|Location.Y=398|Name=21|Designator=C-21|PinPropagationDelay=0.000000E+000
|RECORD=2|OwnerIndex=2381|OwnerPartId=3|FormalType=1|PinConglomerate=56|PinLength=30|Location.X=1250|Location.Y=398|Name=22|Designator=C-22|PinPropagationDelay=0.000000E+000
|RECORD=2|OwnerIndex=2381|OwnerPartId=3|FormalType=1|PinConglomerate=58|PinLength=30|Location.X=1190|Location.Y=388|Name=23|Designator=C-23|PinPropagationDelay=0.000000E+000
|RECORD=2|OwnerIndex=2381|OwnerPartId=3|FormalType=1|PinConglomerate=56|PinLength=30|Location.X=1250|Location.Y=388|Name=24|Designator=C-24|PinPropagationDelay=0.000000E+000
|RECORD=2|OwnerIndex=2381|OwnerPartId=3|FormalType=1|PinConglomerate=58|PinLength=30|Location.X=1190|Location.Y=378|Name=25|Designator=C-25|PinPropagationDelay=0.000000E+000
|RECORD=2|OwnerIndex=2381|OwnerPartId=3|FormalType=1|PinConglomerate=56|PinLength=30|Location.X=1250|Location.Y=378|Name=26|Designator=C-26|PinPropagationDelay=0.000000E+000
|RECORD=2|OwnerIndex=2381|OwnerPartId=3|FormalType=1|PinConglomerate=58|PinLength=30|Location.X=1190|Location.Y=368|Name=27|Designator=C-27|PinPropagationDelay=0.000000E+000
|RECORD=2|OwnerIndex=2381|OwnerPartId=3|FormalType=1|PinConglomerate=56|PinLength=30|Location.X=1250|Location.Y=368|Name=28|Designator=C-28|PinPropagationDelay=0.000000E+000
|RECORD=2|OwnerIndex=2381|OwnerPartId=3|FormalType=1|PinConglomerate=58|PinLength=30|Location.X=1190|Location.Y=358|Name=29|Designator=C-29|PinPropagationDelay=0.000000E+000
|RECORD=2|OwnerIndex=2381|OwnerPartId=3|FormalType=1|PinConglomerate=56|PinLength=30|Location.X=1250|Location.Y=358|Name=30|Designator=C-30|PinPropagationDelay=0.000000E+000
|RECORD=2|OwnerIndex=2381|OwnerPartId=3|FormalType=1|PinConglomerate=58|PinLength=30|Location.X=1190|Location.Y=348|Name=31|Designator=C-31|PinPropagationDelay=0.000000E+000
|RECORD=2|OwnerIndex=2381|OwnerPartId=3|FormalType=1|PinConglomerate=56|PinLength=30|Location.X=1250|Location.Y=348|Name=32|Designator=C-32|PinPropagationDelay=0.000000E+000
|RECORD=2|OwnerIndex=2381|OwnerPartId=3|FormalType=1|PinConglomerate=58|PinLength=30|Location.X=1190|Location.Y=338|Name=33|Designator=C-33|PinPropagationDelay=0.000000E+000
|RECORD=2|OwnerIndex=2381|OwnerPartId=3|FormalType=1|PinConglomerate=56|PinLength=30|Location.X=1250|Location.Y=338|Name=34|Designator=C-34|PinPropagationDelay=0.000000E+000
|RECORD=2|OwnerIndex=2381|OwnerPartId=3|FormalType=1|PinConglomerate=58|PinLength=30|Location.X=1190|Location.Y=328|Name=35|Designator=C-35|PinPropagationDelay=0.000000E+000
|RECORD=2|OwnerIndex=2381|OwnerPartId=3|FormalType=1|PinConglomerate=56|PinLength=30|Location.X=1250|Location.Y=328|Name=36|Designator=C-36|PinPropagationDelay=0.000000E+000
|RECORD=2|OwnerIndex=2381|OwnerPartId=3|FormalType=1|PinConglomerate=58|PinLength=30|Location.X=1190|Location.Y=318|Name=37|Designator=C-37|PinPropagationDelay=0.000000E+000
|RECORD=2|OwnerIndex=2381|OwnerPartId=3|FormalType=1|PinConglomerate=56|PinLength=30|Location.X=1250|Location.Y=318|Name=38|Designator=C-38|PinPropagationDelay=0.000000E+000
|RECORD=2|OwnerIndex=2381|OwnerPartId=3|FormalType=1|PinConglomerate=58|PinLength=30|Location.X=1190|Location.Y=308|Name=39|Designator=C-39|PinPropagationDelay=0.000000E+000
|RECORD=2|OwnerIndex=2381|OwnerPartId=3|FormalType=1|PinConglomerate=56|PinLength=30|Location.X=1250|Location.Y=308|Name=40|Designator=C-40|PinPropagationDelay=0.000000E+000
|RECORD=2|OwnerIndex=2381|OwnerPartId=3|FormalType=1|PinConglomerate=58|PinLength=30|Location.X=1190|Location.Y=298|Name=41|Designator=C-41|PinPropagationDelay=0.000000E+000
|RECORD=2|OwnerIndex=2381|OwnerPartId=3|FormalType=1|PinConglomerate=56|PinLength=30|Location.X=1250|Location.Y=298|Name=42|Designator=C-42|PinPropagationDelay=0.000000E+000
|RECORD=2|OwnerIndex=2381|OwnerPartId=3|FormalType=1|PinConglomerate=58|PinLength=30|Location.X=1190|Location.Y=288|Name=43|Designator=C-43|PinPropagationDelay=0.000000E+000
|RECORD=2|OwnerIndex=2381|OwnerPartId=3|FormalType=1|PinConglomerate=56|PinLength=30|Location.X=1250|Location.Y=288|Name=44|Designator=C-44|PinPropagationDelay=0.000000E+000
|RECORD=2|OwnerIndex=2381|OwnerPartId=3|FormalType=1|PinConglomerate=58|PinLength=30|Location.X=1190|Location.Y=278|Name=45|Designator=C-45|PinPropagationDelay=0.000000E+000
|RECORD=2|OwnerIndex=2381|OwnerPartId=3|FormalType=1|PinConglomerate=56|PinLength=30|Location.X=1250|Location.Y=278|Name=46|Designator=C-46|PinPropagationDelay=0.000000E+000
|RECORD=2|OwnerIndex=2381|OwnerPartId=3|FormalType=1|PinConglomerate=58|PinLength=30|Location.X=1190|Location.Y=268|Name=47|Designator=C-47|PinPropagationDelay=0.000000E+000
|RECORD=2|OwnerIndex=2381|OwnerPartId=3|FormalType=1|PinConglomerate=56|PinLength=30|Location.X=1250|Location.Y=268|Name=48|Designator=C-48|PinPropagationDelay=0.000000E+000
|RECORD=2|OwnerIndex=2381|OwnerPartId=3|FormalType=1|PinConglomerate=58|PinLength=30|Location.X=1190|Location.Y=258|Name=49|Designator=C-49|PinPropagationDelay=0.000000E+000
|RECORD=2|OwnerIndex=2381|OwnerPartId=3|FormalType=1|PinConglomerate=56|PinLength=30|Location.X=1250|Location.Y=258|Name=50|Designator=C-50|PinPropagationDelay=0.000000E+000
|RECORD=2|OwnerIndex=2381|OwnerPartId=3|FormalType=1|PinConglomerate=58|PinLength=30|Location.X=1190|Location.Y=248|Name=51|Designator=C-51|PinPropagationDelay=0.000000E+000
|RECORD=2|OwnerIndex=2381|OwnerPartId=3|FormalType=1|PinConglomerate=56|PinLength=30|Location.X=1250|Location.Y=248|Name=52|Designator=C-52|PinPropagationDelay=0.000000E+000
|RECORD=2|OwnerIndex=2381|OwnerPartId=3|FormalType=1|PinConglomerate=58|PinLength=30|Location.X=1190|Location.Y=238|Name=53|Designator=C-53|PinPropagationDelay=0.000000E+000
|RECORD=2|OwnerIndex=2381|OwnerPartId=3|FormalType=1|PinConglomerate=56|PinLength=30|Location.X=1250|Location.Y=238|Name=54|Designator=C-54|PinPropagationDelay=0.000000E+000
|RECORD=2|OwnerIndex=2381|OwnerPartId=3|FormalType=1|PinConglomerate=58|PinLength=30|Location.X=1190|Location.Y=228|Name=55|Designator=C-55|PinPropagationDelay=0.000000E+000
|RECORD=2|OwnerIndex=2381|OwnerPartId=3|FormalType=1|PinConglomerate=56|PinLength=30|Location.X=1250|Location.Y=228|Name=56|Designator=C-56|PinPropagationDelay=0.000000E+000
|RECORD=2|OwnerIndex=2381|OwnerPartId=3|FormalType=1|PinConglomerate=58|PinLength=30|Location.X=1190|Location.Y=218|Name=57|Designator=C-57|PinPropagationDelay=0.000000E+000
|RECORD=2|OwnerIndex=2381|OwnerPartId=3|FormalType=1|PinConglomerate=56|PinLength=30|Location.X=1250|Location.Y=218|Name=58|Designator=C-58|PinPropagationDelay=0.000000E+000
|RECORD=2|OwnerIndex=2381|OwnerPartId=3|FormalType=1|PinConglomerate=58|PinLength=30|Location.X=1190|Location.Y=208|Name=59|Designator=C-59|PinPropagationDelay=0.000000E+000
|RECORD=2|OwnerIndex=2381|OwnerPartId=3|FormalType=1|PinConglomerate=56|PinLength=30|Location.X=1250|Location.Y=208|Name=60|Designator=C-60|PinPropagationDelay=0.000000E+000
|RECORD=2|OwnerIndex=2381|OwnerPartId=3|FormalType=1|PinConglomerate=58|PinLength=30|Location.X=1190|Location.Y=198|Name=61|Designator=C-61|PinPropagationDelay=0.000000E+000
|RECORD=2|OwnerIndex=2381|OwnerPartId=3|FormalType=1|PinConglomerate=56|PinLength=30|Location.X=1250|Location.Y=198|Name=62|Designator=C-62|PinPropagationDelay=0.000000E+000
|RECORD=2|OwnerIndex=2381|OwnerPartId=3|FormalType=1|PinConglomerate=58|PinLength=30|Location.X=1190|Location.Y=188|Name=63|Designator=C-63|PinPropagationDelay=0.000000E+000
|RECORD=2|OwnerIndex=2381|OwnerPartId=3|FormalType=1|PinConglomerate=56|PinLength=30|Location.X=1250|Location.Y=188|Name=64|Designator=C-64|PinPropagationDelay=0.000000E+000
|RECORD=2|OwnerIndex=2381|OwnerPartId=3|FormalType=1|PinConglomerate=58|PinLength=30|Location.X=1190|Location.Y=178|Name=65|Designator=C-65|PinPropagationDelay=0.000000E+000
|RECORD=2|OwnerIndex=2381|OwnerPartId=3|FormalType=1|PinConglomerate=56|PinLength=30|Location.X=1250|Location.Y=178|Name=66|Designator=C-66|PinPropagationDelay=0.000000E+000
|RECORD=2|OwnerIndex=2381|OwnerPartId=3|FormalType=1|PinConglomerate=58|PinLength=30|Location.X=1190|Location.Y=168|Name=67|Designator=C-67|PinPropagationDelay=0.000000E+000
|RECORD=2|OwnerIndex=2381|OwnerPartId=3|FormalType=1|PinConglomerate=56|PinLength=30|Location.X=1250|Location.Y=168|Name=68|Designator=C-68|PinPropagationDelay=0.000000E+000
|RECORD=2|OwnerIndex=2381|OwnerPartId=3|FormalType=1|PinConglomerate=58|PinLength=30|Location.X=1190|Location.Y=158|Name=69|Designator=C-69|PinPropagationDelay=0.000000E+000
|RECORD=2|OwnerIndex=2381|OwnerPartId=3|FormalType=1|PinConglomerate=56|PinLength=30|Location.X=1250|Location.Y=158|Name=70|Designator=C-70|PinPropagationDelay=0.000000E+000
|RECORD=2|OwnerIndex=2381|OwnerPartId=3|FormalType=1|PinConglomerate=58|PinLength=30|Location.X=1190|Location.Y=148|Name=71|Designator=C-71|PinPropagationDelay=0.000000E+000
|RECORD=2|OwnerIndex=2381|OwnerPartId=3|FormalType=1|PinConglomerate=56|PinLength=30|Location.X=1250|Location.Y=148|Name=72|Designator=C-72|PinPropagationDelay=0.000000E+000
|RECORD=2|OwnerIndex=2381|OwnerPartId=3|FormalType=1|PinConglomerate=58|PinLength=30|Location.X=1190|Location.Y=138|Name=73|Designator=C-73|PinPropagationDelay=0.000000E+000
|RECORD=2|OwnerIndex=2381|OwnerPartId=3|FormalType=1|PinConglomerate=56|PinLength=30|Location.X=1250|Location.Y=138|Name=74|Designator=C-74|PinPropagationDelay=0.000000E+000
|RECORD=2|OwnerIndex=2381|OwnerPartId=3|FormalType=1|PinConglomerate=58|PinLength=30|Location.X=1190|Location.Y=128|Name=75|Designator=C-75|PinPropagationDelay=0.000000E+000
|RECORD=2|OwnerIndex=2381|OwnerPartId=3|FormalType=1|PinConglomerate=56|PinLength=30|Location.X=1250|Location.Y=128|Name=76|Designator=C-76|PinPropagationDelay=0.000000E+000
|RECORD=2|OwnerIndex=2381|OwnerPartId=3|FormalType=1|PinConglomerate=58|PinLength=30|Location.X=1190|Location.Y=118|Name=77|Designator=C-77|PinPropagationDelay=0.000000E+000
|RECORD=2|OwnerIndex=2381|OwnerPartId=3|FormalType=1|PinConglomerate=56|PinLength=30|Location.X=1250|Location.Y=118|Name=78|Designator=C-78|PinPropagationDelay=0.000000E+000
|RECORD=2|OwnerIndex=2381|OwnerPartId=3|FormalType=1|PinConglomerate=58|PinLength=30|Location.X=1190|Location.Y=108|Name=79|Designator=C-79|PinPropagationDelay=0.000000E+000
|RECORD=2|OwnerIndex=2381|OwnerPartId=3|FormalType=1|PinConglomerate=56|PinLength=30|Location.X=1250|Location.Y=108|Name=80|Designator=C-80|PinPropagationDelay=0.000000E+000
|RECORD=2|OwnerIndex=2381|OwnerPartId=3|FormalType=1|PinConglomerate=58|PinLength=30|Location.X=1190|Location.Y=98|Name=81|Designator=C-81|PinPropagationDelay=0.000000E+000
|RECORD=2|OwnerIndex=2381|OwnerPartId=3|FormalType=1|PinConglomerate=56|PinLength=30|Location.X=1250|Location.Y=98|Name=82|Designator=C-82|PinPropagationDelay=0.000000E+000
|RECORD=2|OwnerIndex=2381|OwnerPartId=3|FormalType=1|PinConglomerate=58|PinLength=30|Location.X=1190|Location.Y=88|Name=83|Designator=C-83|PinPropagationDelay=0.000000E+000
|RECORD=2|OwnerIndex=2381|OwnerPartId=3|FormalType=1|PinConglomerate=56|PinLength=30|Location.X=1250|Location.Y=88|Name=84|Designator=C-84|PinPropagationDelay=0.000000E+000
|RECORD=14|OwnerIndex=2381|IsNotAccesible=T|IndexInSheet=170|OwnerPartId=4|Location.X=1190|Location.Y=78|Corner.X=1250|Corner.Y=508|Color=128|AreaColor=11599871|IsSolid=T
|RECORD=2|OwnerIndex=2381|OwnerPartId=4|FormalType=1|PinConglomerate=58|PinLength=30|Location.X=1190|Location.Y=498|Name=1|Designator=D-1|PinPropagationDelay=0.000000E+000
|RECORD=2|OwnerIndex=2381|OwnerPartId=4|FormalType=1|PinConglomerate=56|PinLength=30|Location.X=1250|Location.Y=498|Name=2|Designator=D-2|PinPropagationDelay=0.000000E+000
|RECORD=2|OwnerIndex=2381|OwnerPartId=4|FormalType=1|PinConglomerate=58|PinLength=30|Location.X=1190|Location.Y=488|Name=3|Designator=D-3|PinPropagationDelay=0.000000E+000
|RECORD=2|OwnerIndex=2381|OwnerPartId=4|FormalType=1|PinConglomerate=56|PinLength=30|Location.X=1250|Location.Y=488|Name=4|Designator=D-4|PinPropagationDelay=0.000000E+000
|RECORD=2|OwnerIndex=2381|OwnerPartId=4|FormalType=1|PinConglomerate=58|PinLength=30|Location.X=1190|Location.Y=478|Name=5|Designator=D-5|PinPropagationDelay=0.000000E+000
|RECORD=2|OwnerIndex=2381|OwnerPartId=4|FormalType=1|PinConglomerate=56|PinLength=30|Location.X=1250|Location.Y=478|Name=6|Designator=D-6|PinPropagationDelay=0.000000E+000
|RECORD=2|OwnerIndex=2381|OwnerPartId=4|FormalType=1|PinConglomerate=58|PinLength=30|Location.X=1190|Location.Y=468|Name=7|Designator=D-7|PinPropagationDelay=0.000000E+000
|RECORD=2|OwnerIndex=2381|OwnerPartId=4|FormalType=1|PinConglomerate=56|PinLength=30|Location.X=1250|Location.Y=468|Name=8|Designator=D-8|PinPropagationDelay=0.000000E+000
|RECORD=2|OwnerIndex=2381|OwnerPartId=4|FormalType=1|PinConglomerate=58|PinLength=30|Location.X=1190|Location.Y=458|Name=9|Designator=D-9|PinPropagationDelay=0.000000E+000
|RECORD=2|OwnerIndex=2381|OwnerPartId=4|FormalType=1|PinConglomerate=56|PinLength=30|Location.X=1250|Location.Y=458|Name=10|Designator=D-10|PinPropagationDelay=0.000000E+000
|RECORD=2|OwnerIndex=2381|OwnerPartId=4|FormalType=1|PinConglomerate=58|PinLength=30|Location.X=1190|Location.Y=448|Name=11|Designator=D-11|PinPropagationDelay=0.000000E+000
|RECORD=2|OwnerIndex=2381|OwnerPartId=4|FormalType=1|PinConglomerate=56|PinLength=30|Location.X=1250|Location.Y=448|Name=12|Designator=D-12|PinPropagationDelay=0.000000E+000
|RECORD=2|OwnerIndex=2381|OwnerPartId=4|FormalType=1|PinConglomerate=58|PinLength=30|Location.X=1190|Location.Y=438|Name=13|Designator=D-13|PinPropagationDelay=0.000000E+000
|RECORD=2|OwnerIndex=2381|OwnerPartId=4|FormalType=1|PinConglomerate=56|PinLength=30|Location.X=1250|Location.Y=438|Name=14|Designator=D-14|PinPropagationDelay=0.000000E+000
|RECORD=2|OwnerIndex=2381|OwnerPartId=4|FormalType=1|PinConglomerate=58|PinLength=30|Location.X=1190|Location.Y=428|Name=15|Designator=D-15|PinPropagationDelay=0.000000E+000
|RECORD=2|OwnerIndex=2381|OwnerPartId=4|FormalType=1|PinConglomerate=56|PinLength=30|Location.X=1250|Location.Y=428|Name=16|Designator=D-16|PinPropagationDelay=0.000000E+000
|RECORD=2|OwnerIndex=2381|OwnerPartId=4|FormalType=1|PinConglomerate=58|PinLength=30|Location.X=1190|Location.Y=418|Name=17|Designator=D-17|PinPropagationDelay=0.000000E+000
|RECORD=2|OwnerIndex=2381|OwnerPartId=4|FormalType=1|PinConglomerate=56|PinLength=30|Location.X=1250|Location.Y=418|Name=18|Designator=D-18|PinPropagationDelay=0.000000E+000
|RECORD=2|OwnerIndex=2381|OwnerPartId=4|FormalType=1|PinConglomerate=58|PinLength=30|Location.X=1190|Location.Y=408|Name=19|Designator=D-19|PinPropagationDelay=0.000000E+000
|RECORD=2|OwnerIndex=2381|OwnerPartId=4|FormalType=1|PinConglomerate=56|PinLength=30|Location.X=1250|Location.Y=408|Name=20|Designator=D-20|PinPropagationDelay=0.000000E+000
|RECORD=2|OwnerIndex=2381|OwnerPartId=4|FormalType=1|PinConglomerate=58|PinLength=30|Location.X=1190|Location.Y=398|Name=21|Designator=D-21|PinPropagationDelay=0.000000E+000
|RECORD=2|OwnerIndex=2381|OwnerPartId=4|FormalType=1|PinConglomerate=56|PinLength=30|Location.X=1250|Location.Y=398|Name=22|Designator=D-22|PinPropagationDelay=0.000000E+000
|RECORD=2|OwnerIndex=2381|OwnerPartId=4|FormalType=1|PinConglomerate=58|PinLength=30|Location.X=1190|Location.Y=388|Name=23|Designator=D-23|PinPropagationDelay=0.000000E+000
|RECORD=2|OwnerIndex=2381|OwnerPartId=4|FormalType=1|PinConglomerate=56|PinLength=30|Location.X=1250|Location.Y=388|Name=24|Designator=D-24|PinPropagationDelay=0.000000E+000
|RECORD=2|OwnerIndex=2381|OwnerPartId=4|FormalType=1|PinConglomerate=58|PinLength=30|Location.X=1190|Location.Y=378|Name=25|Designator=D-25|PinPropagationDelay=0.000000E+000
|RECORD=2|OwnerIndex=2381|OwnerPartId=4|FormalType=1|PinConglomerate=56|PinLength=30|Location.X=1250|Location.Y=378|Name=26|Designator=D-26|PinPropagationDelay=0.000000E+000
|RECORD=2|OwnerIndex=2381|OwnerPartId=4|FormalType=1|PinConglomerate=58|PinLength=30|Location.X=1190|Location.Y=368|Name=27|Designator=D-27|PinPropagationDelay=0.000000E+000
|RECORD=2|OwnerIndex=2381|OwnerPartId=4|FormalType=1|PinConglomerate=56|PinLength=30|Location.X=1250|Location.Y=368|Name=28|Designator=D-28|PinPropagationDelay=0.000000E+000
|RECORD=2|OwnerIndex=2381|OwnerPartId=4|FormalType=1|PinConglomerate=58|PinLength=30|Location.X=1190|Location.Y=358|Name=29|Designator=D-29|PinPropagationDelay=0.000000E+000
|RECORD=2|OwnerIndex=2381|OwnerPartId=4|FormalType=1|PinConglomerate=56|PinLength=30|Location.X=1250|Location.Y=358|Name=30|Designator=D-30|PinPropagationDelay=0.000000E+000
|RECORD=2|OwnerIndex=2381|OwnerPartId=4|FormalType=1|PinConglomerate=58|PinLength=30|Location.X=1190|Location.Y=348|Name=31|Designator=D-31|PinPropagationDelay=0.000000E+000
|RECORD=2|OwnerIndex=2381|OwnerPartId=4|FormalType=1|PinConglomerate=56|PinLength=30|Location.X=1250|Location.Y=348|Name=32|Designator=D-32|PinPropagationDelay=0.000000E+000
|RECORD=2|OwnerIndex=2381|OwnerPartId=4|FormalType=1|PinConglomerate=58|PinLength=30|Location.X=1190|Location.Y=338|Name=33|Designator=D-33|PinPropagationDelay=0.000000E+000
|RECORD=2|OwnerIndex=2381|OwnerPartId=4|FormalType=1|PinConglomerate=56|PinLength=30|Location.X=1250|Location.Y=338|Name=34|Designator=D-34|PinPropagationDelay=0.000000E+000
|RECORD=2|OwnerIndex=2381|OwnerPartId=4|FormalType=1|PinConglomerate=58|PinLength=30|Location.X=1190|Location.Y=328|Name=35|Designator=D-35|PinPropagationDelay=0.000000E+000
|RECORD=2|OwnerIndex=2381|OwnerPartId=4|FormalType=1|PinConglomerate=56|PinLength=30|Location.X=1250|Location.Y=328|Name=36|Designator=D-36|PinPropagationDelay=0.000000E+000
|RECORD=2|OwnerIndex=2381|OwnerPartId=4|FormalType=1|PinConglomerate=58|PinLength=30|Location.X=1190|Location.Y=318|Name=37|Designator=D-37|PinPropagationDelay=0.000000E+000
|RECORD=2|OwnerIndex=2381|OwnerPartId=4|FormalType=1|PinConglomerate=56|PinLength=30|Location.X=1250|Location.Y=318|Name=38|Designator=D-38|PinPropagationDelay=0.000000E+000
|RECORD=2|OwnerIndex=2381|OwnerPartId=4|FormalType=1|PinConglomerate=58|PinLength=30|Location.X=1190|Location.Y=308|Name=39|Designator=D-39|PinPropagationDelay=0.000000E+000
|RECORD=2|OwnerIndex=2381|OwnerPartId=4|FormalType=1|PinConglomerate=56|PinLength=30|Location.X=1250|Location.Y=308|Name=40|Designator=D-40|PinPropagationDelay=0.000000E+000
|RECORD=2|OwnerIndex=2381|OwnerPartId=4|FormalType=1|PinConglomerate=58|PinLength=30|Location.X=1190|Location.Y=298|Name=41|Designator=D-41|PinPropagationDelay=0.000000E+000
|RECORD=2|OwnerIndex=2381|OwnerPartId=4|FormalType=1|PinConglomerate=56|PinLength=30|Location.X=1250|Location.Y=298|Name=42|Designator=D-42|PinPropagationDelay=0.000000E+000
|RECORD=2|OwnerIndex=2381|OwnerPartId=4|FormalType=1|PinConglomerate=58|PinLength=30|Location.X=1190|Location.Y=288|Name=43|Designator=D-43|PinPropagationDelay=0.000000E+000
|RECORD=2|OwnerIndex=2381|OwnerPartId=4|FormalType=1|PinConglomerate=56|PinLength=30|Location.X=1250|Location.Y=288|Name=44|Designator=D-44|PinPropagationDelay=0.000000E+000
|RECORD=2|OwnerIndex=2381|OwnerPartId=4|FormalType=1|PinConglomerate=58|PinLength=30|Location.X=1190|Location.Y=278|Name=45|Designator=D-45|PinPropagationDelay=0.000000E+000
|RECORD=2|OwnerIndex=2381|OwnerPartId=4|FormalType=1|PinConglomerate=56|PinLength=30|Location.X=1250|Location.Y=278|Name=46|Designator=D-46|PinPropagationDelay=0.000000E+000
|RECORD=2|OwnerIndex=2381|OwnerPartId=4|FormalType=1|PinConglomerate=58|PinLength=30|Location.X=1190|Location.Y=268|Name=47|Designator=D-47|PinPropagationDelay=0.000000E+000
|RECORD=2|OwnerIndex=2381|OwnerPartId=4|FormalType=1|PinConglomerate=56|PinLength=30|Location.X=1250|Location.Y=268|Name=48|Designator=D-48|PinPropagationDelay=0.000000E+000
|RECORD=2|OwnerIndex=2381|OwnerPartId=4|FormalType=1|PinConglomerate=58|PinLength=30|Location.X=1190|Location.Y=258|Name=49|Designator=D-49|PinPropagationDelay=0.000000E+000
|RECORD=2|OwnerIndex=2381|OwnerPartId=4|FormalType=1|PinConglomerate=56|PinLength=30|Location.X=1250|Location.Y=258|Name=50|Designator=D-50|PinPropagationDelay=0.000000E+000
|RECORD=2|OwnerIndex=2381|OwnerPartId=4|FormalType=1|PinConglomerate=58|PinLength=30|Location.X=1190|Location.Y=248|Name=51|Designator=D-51|PinPropagationDelay=0.000000E+000
|RECORD=2|OwnerIndex=2381|OwnerPartId=4|FormalType=1|PinConglomerate=56|PinLength=30|Location.X=1250|Location.Y=248|Name=52|Designator=D-52|PinPropagationDelay=0.000000E+000
|RECORD=2|OwnerIndex=2381|OwnerPartId=4|FormalType=1|PinConglomerate=58|PinLength=30|Location.X=1190|Location.Y=238|Name=53|Designator=D-53|PinPropagationDelay=0.000000E+000
|RECORD=2|OwnerIndex=2381|OwnerPartId=4|FormalType=1|PinConglomerate=56|PinLength=30|Location.X=1250|Location.Y=238|Name=54|Designator=D-54|PinPropagationDelay=0.000000E+000
|RECORD=2|OwnerIndex=2381|OwnerPartId=4|FormalType=1|PinConglomerate=58|PinLength=30|Location.X=1190|Location.Y=228|Name=55|Designator=D-55|PinPropagationDelay=0.000000E+000
|RECORD=2|OwnerIndex=2381|OwnerPartId=4|FormalType=1|PinConglomerate=56|PinLength=30|Location.X=1250|Location.Y=228|Name=56|Designator=D-56|PinPropagationDelay=0.000000E+000
|RECORD=2|OwnerIndex=2381|OwnerPartId=4|FormalType=1|PinConglomerate=58|PinLength=30|Location.X=1190|Location.Y=218|Name=57|Designator=D-57|PinPropagationDelay=0.000000E+000
|RECORD=2|OwnerIndex=2381|OwnerPartId=4|FormalType=1|PinConglomerate=56|PinLength=30|Location.X=1250|Location.Y=218|Name=58|Designator=D-58|PinPropagationDelay=0.000000E+000
|RECORD=2|OwnerIndex=2381|OwnerPartId=4|FormalType=1|PinConglomerate=58|PinLength=30|Location.X=1190|Location.Y=208|Name=59|Designator=D-59|PinPropagationDelay=0.000000E+000
|RECORD=2|OwnerIndex=2381|OwnerPartId=4|FormalType=1|PinConglomerate=56|PinLength=30|Location.X=1250|Location.Y=208|Name=60|Designator=D-60|PinPropagationDelay=0.000000E+000
|RECORD=2|OwnerIndex=2381|OwnerPartId=4|FormalType=1|PinConglomerate=58|PinLength=30|Location.X=1190|Location.Y=198|Name=61|Designator=D-61|PinPropagationDelay=0.000000E+000
|RECORD=2|OwnerIndex=2381|OwnerPartId=4|FormalType=1|PinConglomerate=56|PinLength=30|Location.X=1250|Location.Y=198|Name=62|Designator=D-62|PinPropagationDelay=0.000000E+000
|RECORD=2|OwnerIndex=2381|OwnerPartId=4|FormalType=1|PinConglomerate=58|PinLength=30|Location.X=1190|Location.Y=188|Name=63|Designator=D-63|PinPropagationDelay=0.000000E+000
|RECORD=2|OwnerIndex=2381|OwnerPartId=4|FormalType=1|PinConglomerate=56|PinLength=30|Location.X=1250|Location.Y=188|Name=64|Designator=D-64|PinPropagationDelay=0.000000E+000
|RECORD=2|OwnerIndex=2381|OwnerPartId=4|FormalType=1|PinConglomerate=58|PinLength=30|Location.X=1190|Location.Y=178|Name=65|Designator=D-65|PinPropagationDelay=0.000000E+000
|RECORD=2|OwnerIndex=2381|OwnerPartId=4|FormalType=1|PinConglomerate=56|PinLength=30|Location.X=1250|Location.Y=178|Name=66|Designator=D-66|PinPropagationDelay=0.000000E+000
|RECORD=2|OwnerIndex=2381|OwnerPartId=4|FormalType=1|PinConglomerate=58|PinLength=30|Location.X=1190|Location.Y=168|Name=67|Designator=D-67|PinPropagationDelay=0.000000E+000
|RECORD=2|OwnerIndex=2381|OwnerPartId=4|FormalType=1|PinConglomerate=56|PinLength=30|Location.X=1250|Location.Y=168|Name=68|Designator=D-68|PinPropagationDelay=0.000000E+000
|RECORD=2|OwnerIndex=2381|OwnerPartId=4|FormalType=1|PinConglomerate=58|PinLength=30|Location.X=1190|Location.Y=158|Name=69|Designator=D-69|PinPropagationDelay=0.000000E+000
|RECORD=2|OwnerIndex=2381|OwnerPartId=4|FormalType=1|PinConglomerate=56|PinLength=30|Location.X=1250|Location.Y=158|Name=70|Designator=D-70|PinPropagationDelay=0.000000E+000
|RECORD=2|OwnerIndex=2381|OwnerPartId=4|FormalType=1|PinConglomerate=58|PinLength=30|Location.X=1190|Location.Y=148|Name=71|Designator=D-71|PinPropagationDelay=0.000000E+000
|RECORD=2|OwnerIndex=2381|OwnerPartId=4|FormalType=1|PinConglomerate=56|PinLength=30|Location.X=1250|Location.Y=148|Name=72|Designator=D-72|PinPropagationDelay=0.000000E+000
|RECORD=2|OwnerIndex=2381|OwnerPartId=4|FormalType=1|PinConglomerate=58|PinLength=30|Location.X=1190|Location.Y=138|Name=73|Designator=D-73|PinPropagationDelay=0.000000E+000
|RECORD=2|OwnerIndex=2381|OwnerPartId=4|FormalType=1|PinConglomerate=56|PinLength=30|Location.X=1250|Location.Y=138|Name=74|Designator=D-74|PinPropagationDelay=0.000000E+000
|RECORD=2|OwnerIndex=2381|OwnerPartId=4|FormalType=1|PinConglomerate=58|PinLength=30|Location.X=1190|Location.Y=128|Name=75|Designator=D-75|PinPropagationDelay=0.000000E+000
|RECORD=2|OwnerIndex=2381|OwnerPartId=4|FormalType=1|PinConglomerate=56|PinLength=30|Location.X=1250|Location.Y=128|Name=76|Designator=D-76|PinPropagationDelay=0.000000E+000
|RECORD=2|OwnerIndex=2381|OwnerPartId=4|FormalType=1|PinConglomerate=58|PinLength=30|Location.X=1190|Location.Y=118|Name=77|Designator=D-77|PinPropagationDelay=0.000000E+000
|RECORD=2|OwnerIndex=2381|OwnerPartId=4|FormalType=1|PinConglomerate=56|PinLength=30|Location.X=1250|Location.Y=118|Name=78|Designator=D-78|PinPropagationDelay=0.000000E+000
|RECORD=2|OwnerIndex=2381|OwnerPartId=4|FormalType=1|PinConglomerate=58|PinLength=30|Location.X=1190|Location.Y=108|Name=79|Designator=D-79|PinPropagationDelay=0.000000E+000
|RECORD=2|OwnerIndex=2381|OwnerPartId=4|FormalType=1|PinConglomerate=56|PinLength=30|Location.X=1250|Location.Y=108|Name=80|Designator=D-80|PinPropagationDelay=0.000000E+000
|RECORD=2|OwnerIndex=2381|OwnerPartId=4|FormalType=1|PinConglomerate=58|PinLength=30|Location.X=1190|Location.Y=98|Name=81|Designator=D-81|PinPropagationDelay=0.000000E+000
|RECORD=2|OwnerIndex=2381|OwnerPartId=4|FormalType=1|PinConglomerate=56|PinLength=30|Location.X=1250|Location.Y=98|Name=82|Designator=D-82|PinPropagationDelay=0.000000E+000
|RECORD=2|OwnerIndex=2381|OwnerPartId=4|FormalType=1|PinConglomerate=58|PinLength=30|Location.X=1190|Location.Y=88|Name=83|Designator=D-83|PinPropagationDelay=0.000000E+000
|RECORD=2|OwnerIndex=2381|OwnerPartId=4|FormalType=1|PinConglomerate=56|PinLength=30|Location.X=1250|Location.Y=88|Name=84|Designator=D-84|PinPropagationDelay=0.000000E+000
|RECORD=14|OwnerIndex=2381|IsNotAccesible=T|IndexInSheet=255|OwnerPartId=1|Location.X=1190|Location.Y=78|Corner.X=1250|Corner.Y=508|Color=128|AreaColor=11599871|IsSolid=T
|RECORD=2|OwnerIndex=2381|OwnerPartId=1|FormalType=1|PinConglomerate=58|PinLength=30|Location.X=1190|Location.Y=498|Name=1|Designator=A-1|PinPropagationDelay=0.000000E+000
|RECORD=2|OwnerIndex=2381|OwnerPartId=1|FormalType=1|PinConglomerate=56|PinLength=30|Location.X=1250|Location.Y=498|Name=2|Designator=A-2|PinPropagationDelay=0.000000E+000
|RECORD=2|OwnerIndex=2381|OwnerPartId=1|FormalType=1|PinConglomerate=58|PinLength=30|Location.X=1190|Location.Y=488|Name=3|Designator=A-3|PinPropagationDelay=0.000000E+000
|RECORD=2|OwnerIndex=2381|OwnerPartId=1|FormalType=1|PinConglomerate=56|PinLength=30|Location.X=1250|Location.Y=488|Name=4|Designator=A-4|PinPropagationDelay=0.000000E+000
|RECORD=2|OwnerIndex=2381|OwnerPartId=1|FormalType=1|PinConglomerate=58|PinLength=30|Location.X=1190|Location.Y=478|Name=5|Designator=A-5|PinPropagationDelay=0.000000E+000
|RECORD=2|OwnerIndex=2381|OwnerPartId=1|FormalType=1|PinConglomerate=56|PinLength=30|Location.X=1250|Location.Y=478|Name=6|Designator=A-6|PinPropagationDelay=0.000000E+000
|RECORD=2|OwnerIndex=2381|OwnerPartId=1|FormalType=1|PinConglomerate=58|PinLength=30|Location.X=1190|Location.Y=468|Name=7|Designator=A-7|PinPropagationDelay=0.000000E+000
|RECORD=2|OwnerIndex=2381|OwnerPartId=1|FormalType=1|PinConglomerate=56|PinLength=30|Location.X=1250|Location.Y=468|Name=8|Designator=A-8|PinPropagationDelay=0.000000E+000
|RECORD=2|OwnerIndex=2381|OwnerPartId=1|FormalType=1|PinConglomerate=58|PinLength=30|Location.X=1190|Location.Y=458|Name=9|Designator=A-9|PinPropagationDelay=0.000000E+000
|RECORD=2|OwnerIndex=2381|OwnerPartId=1|FormalType=1|PinConglomerate=56|PinLength=30|Location.X=1250|Location.Y=458|Name=10|Designator=A-10|PinPropagationDelay=0.000000E+000
|RECORD=2|OwnerIndex=2381|OwnerPartId=1|FormalType=1|PinConglomerate=58|PinLength=30|Location.X=1190|Location.Y=448|Name=11|Designator=A-11|PinPropagationDelay=0.000000E+000
|RECORD=2|OwnerIndex=2381|OwnerPartId=1|FormalType=1|PinConglomerate=56|PinLength=30|Location.X=1250|Location.Y=448|Name=12|Designator=A-12|PinPropagationDelay=0.000000E+000
|RECORD=2|OwnerIndex=2381|OwnerPartId=1|FormalType=1|PinConglomerate=58|PinLength=30|Location.X=1190|Location.Y=438|Name=13|Designator=A-13|PinPropagationDelay=0.000000E+000
|RECORD=2|OwnerIndex=2381|OwnerPartId=1|FormalType=1|PinConglomerate=56|PinLength=30|Location.X=1250|Location.Y=438|Name=14|Designator=A-14|PinPropagationDelay=0.000000E+000
|RECORD=2|OwnerIndex=2381|OwnerPartId=1|FormalType=1|PinConglomerate=58|PinLength=30|Location.X=1190|Location.Y=428|Name=15|Designator=A-15|PinPropagationDelay=0.000000E+000
|RECORD=2|OwnerIndex=2381|OwnerPartId=1|FormalType=1|PinConglomerate=56|PinLength=30|Location.X=1250|Location.Y=428|Name=16|Designator=A-16|PinPropagationDelay=0.000000E+000
|RECORD=2|OwnerIndex=2381|OwnerPartId=1|FormalType=1|PinConglomerate=58|PinLength=30|Location.X=1190|Location.Y=418|Name=17|Designator=A-17|PinPropagationDelay=0.000000E+000
|RECORD=2|OwnerIndex=2381|OwnerPartId=1|FormalType=1|PinConglomerate=56|PinLength=30|Location.X=1250|Location.Y=418|Name=18|Designator=A-18|PinPropagationDelay=0.000000E+000
|RECORD=2|OwnerIndex=2381|OwnerPartId=1|FormalType=1|PinConglomerate=58|PinLength=30|Location.X=1190|Location.Y=408|Name=19|Designator=A-19|PinPropagationDelay=0.000000E+000
|RECORD=2|OwnerIndex=2381|OwnerPartId=1|FormalType=1|PinConglomerate=56|PinLength=30|Location.X=1250|Location.Y=408|Name=20|Designator=A-20|PinPropagationDelay=0.000000E+000
|RECORD=2|OwnerIndex=2381|OwnerPartId=1|FormalType=1|PinConglomerate=58|PinLength=30|Location.X=1190|Location.Y=398|Name=21|Designator=A-21|PinPropagationDelay=0.000000E+000
|RECORD=2|OwnerIndex=2381|OwnerPartId=1|FormalType=1|PinConglomerate=56|PinLength=30|Location.X=1250|Location.Y=398|Name=22|Designator=A-22|PinPropagationDelay=0.000000E+000
|RECORD=2|OwnerIndex=2381|OwnerPartId=1|FormalType=1|PinConglomerate=58|PinLength=30|Location.X=1190|Location.Y=388|Name=23|Designator=A-23|PinPropagationDelay=0.000000E+000
|RECORD=2|OwnerIndex=2381|OwnerPartId=1|FormalType=1|PinConglomerate=56|PinLength=30|Location.X=1250|Location.Y=388|Name=24|Designator=A-24|PinPropagationDelay=0.000000E+000
|RECORD=2|OwnerIndex=2381|OwnerPartId=1|FormalType=1|PinConglomerate=58|PinLength=30|Location.X=1190|Location.Y=378|Name=25|Designator=A-25|PinPropagationDelay=0.000000E+000
|RECORD=2|OwnerIndex=2381|OwnerPartId=1|FormalType=1|PinConglomerate=56|PinLength=30|Location.X=1250|Location.Y=378|Name=26|Designator=A-26|PinPropagationDelay=0.000000E+000
|RECORD=2|OwnerIndex=2381|OwnerPartId=1|FormalType=1|PinConglomerate=58|PinLength=30|Location.X=1190|Location.Y=368|Name=27|Designator=A-27|PinPropagationDelay=0.000000E+000
|RECORD=2|OwnerIndex=2381|OwnerPartId=1|FormalType=1|PinConglomerate=56|PinLength=30|Location.X=1250|Location.Y=368|Name=28|Designator=A-28|PinPropagationDelay=0.000000E+000
|RECORD=2|OwnerIndex=2381|OwnerPartId=1|FormalType=1|PinConglomerate=58|PinLength=30|Location.X=1190|Location.Y=358|Name=29|Designator=A-29|PinPropagationDelay=0.000000E+000
|RECORD=2|OwnerIndex=2381|OwnerPartId=1|FormalType=1|PinConglomerate=56|PinLength=30|Location.X=1250|Location.Y=358|Name=30|Designator=A-30|PinPropagationDelay=0.000000E+000
|RECORD=2|OwnerIndex=2381|OwnerPartId=1|FormalType=1|PinConglomerate=58|PinLength=30|Location.X=1190|Location.Y=348|Name=31|Designator=A-31|PinPropagationDelay=0.000000E+000
|RECORD=2|OwnerIndex=2381|OwnerPartId=1|FormalType=1|PinConglomerate=56|PinLength=30|Location.X=1250|Location.Y=348|Name=32|Designator=A-32|PinPropagationDelay=0.000000E+000
|RECORD=2|OwnerIndex=2381|OwnerPartId=1|FormalType=1|PinConglomerate=58|PinLength=30|Location.X=1190|Location.Y=338|Name=33|Designator=A-33|PinPropagationDelay=0.000000E+000
|RECORD=2|OwnerIndex=2381|OwnerPartId=1|FormalType=1|PinConglomerate=56|PinLength=30|Location.X=1250|Location.Y=338|Name=34|Designator=A-34|PinPropagationDelay=0.000000E+000
|RECORD=2|OwnerIndex=2381|OwnerPartId=1|FormalType=1|PinConglomerate=58|PinLength=30|Location.X=1190|Location.Y=328|Name=35|Designator=A-35|PinPropagationDelay=0.000000E+000
|RECORD=2|OwnerIndex=2381|OwnerPartId=1|FormalType=1|PinConglomerate=56|PinLength=30|Location.X=1250|Location.Y=328|Name=36|Designator=A-36|PinPropagationDelay=0.000000E+000
|RECORD=2|OwnerIndex=2381|OwnerPartId=1|FormalType=1|PinConglomerate=58|PinLength=30|Location.X=1190|Location.Y=318|Name=37|Designator=A-37|PinPropagationDelay=0.000000E+000
|RECORD=2|OwnerIndex=2381|OwnerPartId=1|FormalType=1|PinConglomerate=56|PinLength=30|Location.X=1250|Location.Y=318|Name=38|Designator=A-38|PinPropagationDelay=0.000000E+000
|RECORD=2|OwnerIndex=2381|OwnerPartId=1|FormalType=1|PinConglomerate=58|PinLength=30|Location.X=1190|Location.Y=308|Name=39|Designator=A-39|PinPropagationDelay=0.000000E+000
|RECORD=2|OwnerIndex=2381|OwnerPartId=1|FormalType=1|PinConglomerate=56|PinLength=30|Location.X=1250|Location.Y=308|Name=40|Designator=A-40|PinPropagationDelay=0.000000E+000
|RECORD=2|OwnerIndex=2381|OwnerPartId=1|FormalType=1|PinConglomerate=58|PinLength=30|Location.X=1190|Location.Y=298|Name=41|Designator=A-41|PinPropagationDelay=0.000000E+000
|RECORD=2|OwnerIndex=2381|OwnerPartId=1|FormalType=1|PinConglomerate=56|PinLength=30|Location.X=1250|Location.Y=298|Name=42|Designator=A-42|PinPropagationDelay=0.000000E+000
|RECORD=2|OwnerIndex=2381|OwnerPartId=1|FormalType=1|PinConglomerate=58|PinLength=30|Location.X=1190|Location.Y=288|Name=43|Designator=A-43|PinPropagationDelay=0.000000E+000
|RECORD=2|OwnerIndex=2381|OwnerPartId=1|FormalType=1|PinConglomerate=56|PinLength=30|Location.X=1250|Location.Y=288|Name=44|Designator=A-44|PinPropagationDelay=0.000000E+000
|RECORD=2|OwnerIndex=2381|OwnerPartId=1|FormalType=1|PinConglomerate=58|PinLength=30|Location.X=1190|Location.Y=278|Name=45|Designator=A-45|PinPropagationDelay=0.000000E+000
|RECORD=2|OwnerIndex=2381|OwnerPartId=1|FormalType=1|PinConglomerate=56|PinLength=30|Location.X=1250|Location.Y=278|Name=46|Designator=A-46|PinPropagationDelay=0.000000E+000
|RECORD=2|OwnerIndex=2381|OwnerPartId=1|FormalType=1|PinConglomerate=58|PinLength=30|Location.X=1190|Location.Y=268|Name=47|Designator=A-47|PinPropagationDelay=0.000000E+000
|RECORD=2|OwnerIndex=2381|OwnerPartId=1|FormalType=1|PinConglomerate=56|PinLength=30|Location.X=1250|Location.Y=268|Name=48|Designator=A-48|PinPropagationDelay=0.000000E+000
|RECORD=2|OwnerIndex=2381|OwnerPartId=1|FormalType=1|PinConglomerate=58|PinLength=30|Location.X=1190|Location.Y=258|Name=49|Designator=A-49|PinPropagationDelay=0.000000E+000
|RECORD=2|OwnerIndex=2381|OwnerPartId=1|FormalType=1|PinConglomerate=56|PinLength=30|Location.X=1250|Location.Y=258|Name=50|Designator=A-50|PinPropagationDelay=0.000000E+000
|RECORD=2|OwnerIndex=2381|OwnerPartId=1|FormalType=1|PinConglomerate=58|PinLength=30|Location.X=1190|Location.Y=248|Name=51|Designator=A-51|PinPropagationDelay=0.000000E+000
|RECORD=2|OwnerIndex=2381|OwnerPartId=1|FormalType=1|PinConglomerate=56|PinLength=30|Location.X=1250|Location.Y=248|Name=52|Designator=A-52|PinPropagationDelay=0.000000E+000
|RECORD=2|OwnerIndex=2381|OwnerPartId=1|FormalType=1|PinConglomerate=58|PinLength=30|Location.X=1190|Location.Y=238|Name=53|Designator=A-53|PinPropagationDelay=0.000000E+000
|RECORD=2|OwnerIndex=2381|OwnerPartId=1|FormalType=1|PinConglomerate=56|PinLength=30|Location.X=1250|Location.Y=238|Name=54|Designator=A-54|PinPropagationDelay=0.000000E+000
|RECORD=2|OwnerIndex=2381|OwnerPartId=1|FormalType=1|PinConglomerate=58|PinLength=30|Location.X=1190|Location.Y=228|Name=55|Designator=A-55|PinPropagationDelay=0.000000E+000
|RECORD=2|OwnerIndex=2381|OwnerPartId=1|FormalType=1|PinConglomerate=56|PinLength=30|Location.X=1250|Location.Y=228|Name=56|Designator=A-56|PinPropagationDelay=0.000000E+000
|RECORD=2|OwnerIndex=2381|OwnerPartId=1|FormalType=1|PinConglomerate=58|PinLength=30|Location.X=1190|Location.Y=218|Name=57|Designator=A-57|PinPropagationDelay=0.000000E+000
|RECORD=2|OwnerIndex=2381|OwnerPartId=1|FormalType=1|PinConglomerate=56|PinLength=30|Location.X=1250|Location.Y=218|Name=58|Designator=A-58|PinPropagationDelay=0.000000E+000
|RECORD=2|OwnerIndex=2381|OwnerPartId=1|FormalType=1|PinConglomerate=58|PinLength=30|Location.X=1190|Location.Y=208|Name=59|Designator=A-59|PinPropagationDelay=0.000000E+000
|RECORD=2|OwnerIndex=2381|OwnerPartId=1|FormalType=1|PinConglomerate=56|PinLength=30|Location.X=1250|Location.Y=208|Name=60|Designator=A-60|PinPropagationDelay=0.000000E+000
|RECORD=2|OwnerIndex=2381|OwnerPartId=1|FormalType=1|PinConglomerate=58|PinLength=30|Location.X=1190|Location.Y=198|Name=61|Designator=A-61|PinPropagationDelay=0.000000E+000
|RECORD=2|OwnerIndex=2381|OwnerPartId=1|FormalType=1|PinConglomerate=56|PinLength=30|Location.X=1250|Location.Y=198|Name=62|Designator=A-62|PinPropagationDelay=0.000000E+000
|RECORD=2|OwnerIndex=2381|OwnerPartId=1|FormalType=1|PinConglomerate=58|PinLength=30|Location.X=1190|Location.Y=188|Name=63|Designator=A-63|PinPropagationDelay=0.000000E+000
|RECORD=2|OwnerIndex=2381|OwnerPartId=1|FormalType=1|PinConglomerate=56|PinLength=30|Location.X=1250|Location.Y=188|Name=64|Designator=A-64|PinPropagationDelay=0.000000E+000
|RECORD=2|OwnerIndex=2381|OwnerPartId=1|FormalType=1|PinConglomerate=58|PinLength=30|Location.X=1190|Location.Y=178|Name=65|Designator=A-65|PinPropagationDelay=0.000000E+000
|RECORD=2|OwnerIndex=2381|OwnerPartId=1|FormalType=1|PinConglomerate=56|PinLength=30|Location.X=1250|Location.Y=178|Name=66|Designator=A-66|PinPropagationDelay=0.000000E+000
|RECORD=2|OwnerIndex=2381|OwnerPartId=1|FormalType=1|PinConglomerate=58|PinLength=30|Location.X=1190|Location.Y=168|Name=67|Designator=A-67|PinPropagationDelay=0.000000E+000
|RECORD=2|OwnerIndex=2381|OwnerPartId=1|FormalType=1|PinConglomerate=56|PinLength=30|Location.X=1250|Location.Y=168|Name=68|Designator=A-68|PinPropagationDelay=0.000000E+000
|RECORD=2|OwnerIndex=2381|OwnerPartId=1|FormalType=1|PinConglomerate=58|PinLength=30|Location.X=1190|Location.Y=158|Name=69|Designator=A-69|PinPropagationDelay=0.000000E+000
|RECORD=2|OwnerIndex=2381|OwnerPartId=1|FormalType=1|PinConglomerate=56|PinLength=30|Location.X=1250|Location.Y=158|Name=70|Designator=A-70|PinPropagationDelay=0.000000E+000
|RECORD=2|OwnerIndex=2381|OwnerPartId=1|FormalType=1|PinConglomerate=58|PinLength=30|Location.X=1190|Location.Y=148|Name=71|Designator=A-71|PinPropagationDelay=0.000000E+000
|RECORD=2|OwnerIndex=2381|OwnerPartId=1|FormalType=1|PinConglomerate=56|PinLength=30|Location.X=1250|Location.Y=148|Name=72|Designator=A-72|PinPropagationDelay=0.000000E+000
|RECORD=2|OwnerIndex=2381|OwnerPartId=1|FormalType=1|PinConglomerate=58|PinLength=30|Location.X=1190|Location.Y=138|Name=73|Designator=A-73|PinPropagationDelay=0.000000E+000
|RECORD=2|OwnerIndex=2381|OwnerPartId=1|FormalType=1|PinConglomerate=56|PinLength=30|Location.X=1250|Location.Y=138|Name=74|Designator=A-74|PinPropagationDelay=0.000000E+000
|RECORD=2|OwnerIndex=2381|OwnerPartId=1|FormalType=1|PinConglomerate=58|PinLength=30|Location.X=1190|Location.Y=128|Name=75|Designator=A-75|PinPropagationDelay=0.000000E+000
|RECORD=2|OwnerIndex=2381|OwnerPartId=1|FormalType=1|PinConglomerate=56|PinLength=30|Location.X=1250|Location.Y=128|Name=76|Designator=A-76|PinPropagationDelay=0.000000E+000
|RECORD=2|OwnerIndex=2381|OwnerPartId=1|FormalType=1|PinConglomerate=58|PinLength=30|Location.X=1190|Location.Y=118|Name=77|Designator=A-77|PinPropagationDelay=0.000000E+000
|RECORD=2|OwnerIndex=2381|OwnerPartId=1|FormalType=1|PinConglomerate=56|PinLength=30|Location.X=1250|Location.Y=118|Name=78|Designator=A-78|PinPropagationDelay=0.000000E+000
|RECORD=2|OwnerIndex=2381|OwnerPartId=1|FormalType=1|PinConglomerate=58|PinLength=30|Location.X=1190|Location.Y=108|Name=79|Designator=A-79|PinPropagationDelay=0.000000E+000
|RECORD=2|OwnerIndex=2381|OwnerPartId=1|FormalType=1|PinConglomerate=56|PinLength=30|Location.X=1250|Location.Y=108|Name=80|Designator=A-80|PinPropagationDelay=0.000000E+000
|RECORD=2|OwnerIndex=2381|OwnerPartId=1|FormalType=1|PinConglomerate=58|PinLength=30|Location.X=1190|Location.Y=98|Name=81|Designator=A-81|PinPropagationDelay=0.000000E+000
|RECORD=2|OwnerIndex=2381|OwnerPartId=1|FormalType=1|PinConglomerate=56|PinLength=30|Location.X=1250|Location.Y=98|Name=82|Designator=A-82|PinPropagationDelay=0.000000E+000
|RECORD=2|OwnerIndex=2381|OwnerPartId=1|FormalType=1|PinConglomerate=58|PinLength=30|Location.X=1190|Location.Y=88|Name=83|Designator=A-83|PinPropagationDelay=0.000000E+000
|RECORD=2|OwnerIndex=2381|OwnerPartId=1|FormalType=1|PinConglomerate=56|PinLength=30|Location.X=1250|Location.Y=88|Name=84|Designator=A-84|PinPropagationDelay=0.000000E+000
|RECORD=34|OwnerIndex=2381|IndexInSheet=-1|OwnerPartId=-1|Location.X=1190|Location.Y=508|Color=8388608|FontID=1|Text=P1|Name=Designator|ReadOnlyState=1
|RECORD=41|OwnerIndex=2381|IndexInSheet=-1|OwnerPartId=-1|Location.X=1190|Location.Y=68|Color=8388608|FontID=1|Text=FPGA_CONN|Name=Comment
|RECORD=44|OwnerIndex=2381
|RECORD=45|OwnerIndex=3060|IndexInSheet=-1|ModelName=FPGA_CONN|ModelType=PCBLIB|DatafileCount=1|ModelDatafileEntity0=FPGA_CONN|ModelDatafileKind0=PCBLib|IsCurrent=T
|RECORD=46|OwnerIndex=3061
|RECORD=48|OwnerIndex=3061
|RECORD=17|IndexInSheet=307|OwnerPartId=-1|ShowNetName=T|Location.X=640|Location.Y=778|Color=255|FontID=1|Text=EXT_EEPROM_WP|IsCrossSheetConnector=T
|RECORD=41|IndexInSheet=308|OwnerPartId=-1|Color=8388608|FontID=1|IsHidden=T|Name=ConfigurationParameters|ReadOnlyState=1
|RECORD=41|IndexInSheet=309|OwnerPartId=-1|Color=8388608|FontID=1|IsHidden=T|Name=ConfiguratorName|ReadOnlyState=1
|RECORD=41|IndexInSheet=310|OwnerPartId=-1|Color=8388608|FontID=1|IsHidden=T|Name=VersionControl_RevNumber|ReadOnlyState=1
|RECORD=41|IndexInSheet=311|OwnerPartId=-1|Color=8388608|FontID=1|IsHidden=T|Name=IsUserConfigurable|ReadOnlyState=1
|RECORD=41|IndexInSheet=312|OwnerPartId=-1|Color=8388608|FontID=1|IsHidden=T|Name=VersionControl_ProjFolderRevNumber|ReadOnlyState=1
|RECORD=41|IndexInSheet=313|OwnerPartId=-1|Color=8388608|FontID=1|IsHidden=T|Name=SPICEModelCache|ReadOnlyState=1
|RECORD=22|IndexInSheet=314|OwnerPartId=-1|Location.X=1290|Location.Y=968|Color=255|Orientation=1|Symbol=Thin Cross|IsActive=T|SuppressAll=T
|RECORD=27|IndexInSheet=315|OwnerPartId=-1|LineWidth=1|Color=8388608|LocationCount=2|X1=1170|Y1=828|X2=1060|Y2=828
|RECORD=27|IndexInSheet=316|OwnerPartId=-1|LineWidth=1|Color=8388608|LocationCount=2|X1=320|Y1=108|X2=460|Y2=108
|RECORD=27|IndexInSheet=317|OwnerPartId=-1|LineWidth=1|Color=8388608|LocationCount=2|X1=320|Y1=118|X2=460|Y2=118
|RECORD=27|IndexInSheet=318|OwnerPartId=-1|LineWidth=1|Color=8388608|LocationCount=2|X1=320|Y1=388|X2=460|Y2=388
|RECORD=27|IndexInSheet=319|OwnerPartId=-1|LineWidth=1|Color=8388608|LocationCount=2|X1=320|Y1=398|X2=460|Y2=398
|RECORD=27|IndexInSheet=320|OwnerPartId=-1|LineWidth=1|Color=8388608|LocationCount=2|X1=460|Y1=608|X2=330|Y2=608
|RECORD=27|IndexInSheet=321|OwnerPartId=-1|LineWidth=1|Color=8388608|LocationCount=2|X1=460|Y1=618|X2=330|Y2=618
|RECORD=27|IndexInSheet=322|OwnerPartId=-1|LineWidth=1|Color=8388608|LocationCount=2|X1=460|Y1=628|X2=330|Y2=628
|RECORD=27|IndexInSheet=323|OwnerPartId=-1|LineWidth=1|Color=8388608|LocationCount=2|X1=460|Y1=638|X2=330|Y2=638
|RECORD=27|IndexInSheet=324|OwnerPartId=-1|LineWidth=1|Color=8388608|LocationCount=2|X1=460|Y1=658|X2=330|Y2=658
|RECORD=27|IndexInSheet=325|OwnerPartId=-1|LineWidth=1|Color=8388608|LocationCount=2|X1=460|Y1=158|X2=400|Y2=158
|RECORD=27|IndexInSheet=326|OwnerPartId=-1|LineWidth=1|Color=8388608|LocationCount=2|X1=460|Y1=208|X2=400|Y2=208
|RECORD=27|IndexInSheet=327|OwnerPartId=-1|LineWidth=1|Color=8388608|LocationCount=2|X1=460|Y1=258|X2=400|Y2=258
|RECORD=27|IndexInSheet=328|OwnerPartId=-1|LineWidth=1|Color=8388608|LocationCount=2|X1=460|Y1=308|X2=400|Y2=308
|RECORD=27|IndexInSheet=329|OwnerPartId=-1|LineWidth=1|Color=8388608|LocationCount=2|X1=460|Y1=358|X2=400|Y2=358
|RECORD=27|IndexInSheet=330|OwnerPartId=-1|LineWidth=1|Color=8388608|LocationCount=2|X1=460|Y1=408|X2=400|Y2=408
|RECORD=27|IndexInSheet=331|OwnerPartId=-1|LineWidth=1|Color=8388608|LocationCount=9|X1=460|Y1=458|X2=400|Y2=458|X3=400|Y3=408|X4=400|Y4=358|X5=400|Y5=308|X6=400|Y6=258|X7=400|Y7=208|X8=400|Y8=158|X9=400|Y9=68
|RECORD=27|IndexInSheet=332|OwnerPartId=-1|LineWidth=1|Color=8388608|LocationCount=2|X1=460|Y1=648|X2=410|Y2=648
|RECORD=27|IndexInSheet=333|OwnerPartId=-1|LineWidth=1|Color=8388608|LocationCount=2|X1=460|Y1=698|X2=410|Y2=698
|RECORD=27|IndexInSheet=334|OwnerPartId=-1|LineWidth=1|Color=8388608|LocationCount=2|X1=460|Y1=748|X2=410|Y2=748
|RECORD=27|IndexInSheet=335|OwnerPartId=-1|LineWidth=1|Color=8388608|LocationCount=2|X1=460|Y1=798|X2=410|Y2=798
|RECORD=27|IndexInSheet=336|OwnerPartId=-1|LineWidth=1|Color=8388608|LocationCount=2|X1=460|Y1=848|X2=410|Y2=848
|RECORD=27|IndexInSheet=337|OwnerPartId=-1|LineWidth=1|Color=8388608|LocationCount=2|X1=460|Y1=898|X2=410|Y2=898
|RECORD=27|IndexInSheet=338|OwnerPartId=-1|LineWidth=1|Color=8388608|LocationCount=9|X1=460|Y1=948|X2=410|Y2=948|X3=410|Y3=898|X4=410|Y4=848|X5=410|Y5=798|X6=410|Y6=748|X7=410|Y7=698|X8=410|Y8=648|X9=410|Y9=568
|RECORD=27|IndexInSheet=339|OwnerPartId=-1|LineWidth=1|Color=8388608|LocationCount=6|X1=460|Y1=958|X2=410|Y2=958|X3=410|Y3=968|X4=410|Y4=978|X5=410|Y5=988|X6=410|Y6=1008
|RECORD=27|IndexInSheet=340|OwnerPartId=-1|LineWidth=1|Color=8388608|LocationCount=2|X1=460|Y1=968|X2=410|Y2=968
|RECORD=27|IndexInSheet=341|OwnerPartId=-1|LineWidth=1|Color=8388608|LocationCount=2|X1=460|Y1=978|X2=410|Y2=978
|RECORD=27|IndexInSheet=342|OwnerPartId=-1|LineWidth=1|Color=8388608|LocationCount=2|X1=460|Y1=988|X2=410|Y2=988
|RECORD=27|IndexInSheet=343|OwnerPartId=-1|LineWidth=1|Color=8388608|LocationCount=2|X1=580|Y1=108|X2=690|Y2=108
|RECORD=27|IndexInSheet=344|OwnerPartId=-1|LineWidth=1|Color=8388608|LocationCount=2|X1=580|Y1=118|X2=690|Y2=118
|RECORD=27|IndexInSheet=345|OwnerPartId=-1|LineWidth=1|Color=8388608|LocationCount=2|X1=580|Y1=158|X2=620|Y2=158
|RECORD=27|IndexInSheet=346|OwnerPartId=-1|LineWidth=1|Color=8388608|LocationCount=2|X1=580|Y1=208|X2=620|Y2=208
|RECORD=27|IndexInSheet=347|OwnerPartId=-1|LineWidth=1|Color=8388608|LocationCount=2|X1=580|Y1=258|X2=620|Y2=258
|RECORD=27|IndexInSheet=348|OwnerPartId=-1|LineWidth=1|Color=8388608|LocationCount=2|X1=580|Y1=308|X2=620|Y2=308
|RECORD=27|IndexInSheet=349|OwnerPartId=-1|LineWidth=1|Color=8388608|LocationCount=2|X1=580|Y1=358|X2=620|Y2=358
|RECORD=27|IndexInSheet=350|OwnerPartId=-1|LineWidth=1|Color=8388608|LocationCount=2|X1=580|Y1=408|X2=620|Y2=408
|RECORD=27|IndexInSheet=351|OwnerPartId=-1|LineWidth=1|Color=8388608|LocationCount=2|X1=580|Y1=648|X2=600|Y2=648
|RECORD=27|IndexInSheet=352|OwnerPartId=-1|LineWidth=1|Color=8388608|LocationCount=2|X1=640|Y1=678|X2=580|Y2=678
|RECORD=27|IndexInSheet=353|OwnerPartId=-1|LineWidth=1|Color=8388608|LocationCount=2|X1=640|Y1=688|X2=580|Y2=688
|RECORD=27|IndexInSheet=354|OwnerPartId=-1|LineWidth=1|Color=8388608|LocationCount=2|X1=580|Y1=698|X2=600|Y2=698
|RECORD=27|IndexInSheet=355|OwnerPartId=-1|LineWidth=1|Color=8388608|LocationCount=2|X1=640|Y1=718|X2=580|Y2=718
|RECORD=27|IndexInSheet=356|OwnerPartId=-1|LineWidth=1|Color=8388608|LocationCount=2|X1=640|Y1=728|X2=580|Y2=728
|RECORD=27|IndexInSheet=357|OwnerPartId=-1|LineWidth=1|Color=8388608|LocationCount=2|X1=580|Y1=748|X2=600|Y2=748
|RECORD=27|IndexInSheet=358|OwnerPartId=-1|LineWidth=1|Color=8388608|LocationCount=2|X1=640|Y1=758|X2=580|Y2=758
|RECORD=27|IndexInSheet=359|OwnerPartId=-1|LineWidth=1|Color=8388608|LocationCount=2|X1=640|Y1=768|X2=580|Y2=768
|RECORD=27|IndexInSheet=360|OwnerPartId=-1|LineWidth=1|Color=8388608|LocationCount=2|X1=580|Y1=798|X2=600|Y2=798
|RECORD=27|IndexInSheet=361|OwnerPartId=-1|LineWidth=1|Color=8388608|LocationCount=2|X1=640|Y1=828|X2=580|Y2=828
|RECORD=27|IndexInSheet=362|OwnerPartId=-1|LineWidth=1|Color=8388608|LocationCount=2|X1=640|Y1=838|X2=580|Y2=838
|RECORD=27|IndexInSheet=363|OwnerPartId=-1|LineWidth=1|Color=8388608|LocationCount=2|X1=580|Y1=848|X2=600|Y2=848
|RECORD=27|IndexInSheet=364|OwnerPartId=-1|LineWidth=1|Color=8388608|LocationCount=2|X1=640|Y1=888|X2=580|Y2=888
|RECORD=27|IndexInSheet=365|OwnerPartId=-1|LineWidth=1|Color=8388608|LocationCount=2|X1=580|Y1=898|X2=600|Y2=898
|RECORD=27|IndexInSheet=366|OwnerPartId=-1|LineWidth=1|Color=8388608|LocationCount=2|X1=580|Y1=968|X2=600|Y2=968
|RECORD=27|IndexInSheet=367|OwnerPartId=-1|LineWidth=1|Color=8388608|LocationCount=2|X1=580|Y1=978|X2=600|Y2=978
|RECORD=27|IndexInSheet=368|OwnerPartId=-1|LineWidth=1|Color=8388608|LocationCount=2|X1=580|Y1=988|X2=600|Y2=988
|RECORD=27|IndexInSheet=369|OwnerPartId=-1|LineWidth=1|Color=8388608|LocationCount=2|X1=1160|Y1=318|X2=1060|Y2=318
|RECORD=27|IndexInSheet=370|OwnerPartId=-1|LineWidth=1|Color=8388608|LocationCount=2|X1=1160|Y1=328|X2=1060|Y2=328
|RECORD=27|IndexInSheet=371|OwnerPartId=-1|LineWidth=1|Color=8388608|LocationCount=2|X1=1160|Y1=348|X2=1060|Y2=348
|RECORD=27|IndexInSheet=372|OwnerPartId=-1|LineWidth=1|Color=8388608|LocationCount=2|X1=1160|Y1=358|X2=1060|Y2=358
|RECORD=27|IndexInSheet=373|OwnerPartId=-1|LineWidth=1|Color=8388608|LocationCount=2|X1=1160|Y1=378|X2=1060|Y2=378
|RECORD=27|IndexInSheet=374|OwnerPartId=-1|LineWidth=1|Color=8388608|LocationCount=2|X1=1160|Y1=388|X2=1060|Y2=388
|RECORD=27|IndexInSheet=375|OwnerPartId=-1|LineWidth=1|Color=8388608|LocationCount=2|X1=1160|Y1=408|X2=1060|Y2=408
|RECORD=27|IndexInSheet=376|OwnerPartId=-1|LineWidth=1|Color=8388608|LocationCount=2|X1=1160|Y1=418|X2=1060|Y2=418
|RECORD=27|IndexInSheet=377|OwnerPartId=-1|LineWidth=1|Color=8388608|LocationCount=2|X1=1170|Y1=598|X2=1060|Y2=598
|RECORD=27|IndexInSheet=378|OwnerPartId=-1|LineWidth=1|Color=8388608|LocationCount=2|X1=1060|Y1=658|X2=1170|Y2=658
|RECORD=27|IndexInSheet=379|OwnerPartId=-1|LineWidth=1|Color=8388608|LocationCount=2|X1=1060|Y1=688|X2=1170|Y2=688
|RECORD=27|IndexInSheet=380|OwnerPartId=-1|LineWidth=1|Color=8388608|LocationCount=2|X1=1060|Y1=758|X2=1170|Y2=758
|RECORD=27|IndexInSheet=381|OwnerPartId=-1|LineWidth=1|Color=8388608|LocationCount=2|X1=1060|Y1=778|X2=1170|Y2=778
|RECORD=27|IndexInSheet=382|OwnerPartId=-1|LineWidth=1|Color=8388608|LocationCount=2|X1=1170|Y1=808|X2=1060|Y2=808
|RECORD=27|IndexInSheet=383|OwnerPartId=-1|LineWidth=1|Color=8388608|LocationCount=2|X1=1170|Y1=818|X2=1060|Y2=818
|RECORD=27|IndexInSheet=384|OwnerPartId=-1|LineWidth=1|Color=8388608|LocationCount=2|X1=1060|Y1=858|X2=1170|Y2=858
|RECORD=27|IndexInSheet=385|OwnerPartId=-1|LineWidth=1|Color=8388608|LocationCount=2|X1=1060|Y1=868|X2=1170|Y2=868
|RECORD=27|IndexInSheet=386|OwnerPartId=-1|LineWidth=1|Color=8388608|LocationCount=2|X1=1060|Y1=878|X2=1170|Y2=878
|RECORD=27|IndexInSheet=387|OwnerPartId=-1|LineWidth=1|Color=8388608|LocationCount=2|X1=1060|Y1=888|X2=1170|Y2=888
|RECORD=27|IndexInSheet=388|OwnerPartId=-1|LineWidth=1|Color=8388608|LocationCount=3|X1=1060|Y1=938|X2=1160|Y2=938|X3=1170|Y3=938
|RECORD=27|IndexInSheet=389|OwnerPartId=-1|LineWidth=1|Color=8388608|LocationCount=2|X1=1160|Y1=158|X2=1110|Y2=158
|RECORD=27|IndexInSheet=390|OwnerPartId=-1|LineWidth=1|Color=8388608|LocationCount=2|X1=1160|Y1=208|X2=1110|Y2=208
|RECORD=27|IndexInSheet=391|OwnerPartId=-1|LineWidth=1|Color=8388608|LocationCount=2|X1=1160|Y1=258|X2=1110|Y2=258
|RECORD=27|IndexInSheet=392|OwnerPartId=-1|LineWidth=1|Color=8388608|LocationCount=2|X1=1160|Y1=308|X2=1110|Y2=308
|RECORD=27|IndexInSheet=393|OwnerPartId=-1|LineWidth=1|Color=8388608|LocationCount=2|X1=1160|Y1=338|X2=1110|Y2=338
|RECORD=27|IndexInSheet=394|OwnerPartId=-1|LineWidth=1|Color=8388608|LocationCount=2|X1=1160|Y1=368|X2=1110|Y2=368
|RECORD=27|IndexInSheet=395|OwnerPartId=-1|LineWidth=1|Color=8388608|LocationCount=2|X1=1160|Y1=398|X2=1110|Y2=398
|RECORD=27|IndexInSheet=396|OwnerPartId=-1|LineWidth=1|Color=8388608|LocationCount=2|X1=1160|Y1=428|X2=1110|Y2=428
|RECORD=27|IndexInSheet=397|OwnerPartId=-1|LineWidth=1|Color=8388608|LocationCount=11|X1=1160|Y1=458|X2=1110|Y2=458|X3=1110|Y3=428|X4=1110|Y4=398|X5=1110|Y5=368|X6=1110|Y6=338|X7=1110|Y7=308|X8=1110|Y8=258|X9=1110|Y9=208|X10=1110|Y10=158|X11=1110|Y11=78
|RECORD=27|IndexInSheet=398|OwnerPartId=-1|LineWidth=1|Color=8388608|LocationCount=2|X1=1170|Y1=648|X2=1130|Y2=648
|RECORD=27|IndexInSheet=399|OwnerPartId=-1|LineWidth=1|Color=8388608|LocationCount=2|X1=1170|Y1=698|X2=1130|Y2=698
|RECORD=27|IndexInSheet=400|OwnerPartId=-1|LineWidth=1|Color=8388608|LocationCount=2|X1=1170|Y1=748|X2=1130|Y2=748
|RECORD=27|IndexInSheet=401|OwnerPartId=-1|LineWidth=1|Color=8388608|LocationCount=2|X1=1170|Y1=798|X2=1130|Y2=798
|RECORD=27|IndexInSheet=402|OwnerPartId=-1|LineWidth=1|Color=8388608|LocationCount=2|X1=1170|Y1=848|X2=1130|Y2=848
|RECORD=27|IndexInSheet=403|OwnerPartId=-1|LineWidth=1|Color=8388608|LocationCount=2|X1=1170|Y1=898|X2=1130|Y2=898
|RECORD=27|IndexInSheet=404|OwnerPartId=-1|LineWidth=1|Color=8388608|LocationCount=9|X1=1170|Y1=948|X2=1130|Y2=948|X3=1130|Y3=898|X4=1130|Y4=848|X5=1130|Y5=798|X6=1130|Y6=748|X7=1130|Y7=698|X8=1130|Y8=648|X9=1130|Y9=568
|RECORD=27|IndexInSheet=405|OwnerPartId=-1|LineWidth=1|Color=8388608|LocationCount=3|X1=1170|Y1=928|X2=1160|Y2=928|X3=1160|Y3=938
|RECORD=27|IndexInSheet=406|OwnerPartId=-1|LineWidth=1|Color=8388608|LocationCount=2|X1=1280|Y1=158|X2=1310|Y2=158
|RECORD=27|IndexInSheet=407|OwnerPartId=-1|LineWidth=1|Color=8388608|LocationCount=2|X1=1280|Y1=208|X2=1310|Y2=208
|RECORD=27|IndexInSheet=408|OwnerPartId=-1|LineWidth=1|Color=8388608|LocationCount=2|X1=1280|Y1=258|X2=1310|Y2=258
|RECORD=27|IndexInSheet=409|OwnerPartId=-1|LineWidth=1|Color=8388608|LocationCount=2|X1=1280|Y1=308|X2=1310|Y2=308
|RECORD=27|IndexInSheet=410|OwnerPartId=-1|LineWidth=1|Color=8388608|LocationCount=2|X1=1280|Y1=318|X2=1360|Y2=318
|RECORD=27|IndexInSheet=411|OwnerPartId=-1|LineWidth=1|Color=8388608|LocationCount=2|X1=1280|Y1=328|X2=1360|Y2=328
|RECORD=27|IndexInSheet=412|OwnerPartId=-1|LineWidth=1|Color=8388608|LocationCount=2|X1=1280|Y1=348|X2=1360|Y2=348
|RECORD=27|IndexInSheet=413|OwnerPartId=-1|LineWidth=1|Color=8388608|LocationCount=2|X1=1280|Y1=358|X2=1360|Y2=358
|RECORD=27|IndexInSheet=414|OwnerPartId=-1|LineWidth=1|Color=8388608|LocationCount=2|X1=1280|Y1=378|X2=1360|Y2=378
|RECORD=27|IndexInSheet=415|OwnerPartId=-1|LineWidth=1|Color=8388608|LocationCount=2|X1=1280|Y1=388|X2=1360|Y2=388
|RECORD=27|IndexInSheet=416|OwnerPartId=-1|LineWidth=1|Color=8388608|LocationCount=2|X1=1280|Y1=408|X2=1360|Y2=408
|RECORD=27|IndexInSheet=417|OwnerPartId=-1|LineWidth=1|Color=8388608|LocationCount=2|X1=1280|Y1=418|X2=1360|Y2=418
|RECORD=27|IndexInSheet=418|OwnerPartId=-1|LineWidth=1|Color=8388608|LocationCount=2|X1=1280|Y1=438|X2=1360|Y2=438
|RECORD=27|IndexInSheet=419|OwnerPartId=-1|LineWidth=1|Color=8388608|LocationCount=2|X1=1280|Y1=448|X2=1360|Y2=448
|RECORD=27|IndexInSheet=420|OwnerPartId=-1|LineWidth=1|Color=8388608|LocationCount=2|X1=1290|Y1=648|X2=1320|Y2=648
|RECORD=27|IndexInSheet=421|OwnerPartId=-1|LineWidth=1|Color=8388608|LocationCount=2|X1=1290|Y1=698|X2=1320|Y2=698
|RECORD=27|IndexInSheet=422|OwnerPartId=-1|LineWidth=1|Color=8388608|LocationCount=2|X1=1290|Y1=748|X2=1320|Y2=748
|RECORD=27|IndexInSheet=423|OwnerPartId=-1|LineWidth=1|Color=8388608|LocationCount=2|X1=1290|Y1=798|X2=1320|Y2=798
|RECORD=27|IndexInSheet=424|OwnerPartId=-1|LineWidth=1|Color=8388608|LocationCount=2|X1=1290|Y1=848|X2=1320|Y2=848
|RECORD=27|IndexInSheet=425|OwnerPartId=-1|LineWidth=1|Color=8388608|LocationCount=2|X1=1290|Y1=898|X2=1320|Y2=898
|RECORD=27|IndexInSheet=426|OwnerPartId=-1|LineWidth=1|Color=8388608|LocationCount=2|X1=1350|Y1=958|X2=1290|Y2=958
|RECORD=27|IndexInSheet=427|OwnerPartId=-1|LineWidth=1|Color=8388608|LocationCount=9|X1=580|Y1=948|X2=600|Y2=948|X3=600|Y3=898|X4=600|Y4=848|X5=600|Y5=798|X6=600|Y6=748|X7=600|Y7=698|X8=600|Y8=648|X9=600|Y9=568
|RECORD=27|IndexInSheet=428|OwnerPartId=-1|LineWidth=1|Color=8388608|LocationCount=6|X1=580|Y1=958|X2=600|Y2=958|X3=600|Y3=968|X4=600|Y4=978|X5=600|Y5=988|X6=600|Y6=1008
|RECORD=27|IndexInSheet=429|OwnerPartId=-1|LineWidth=1|Color=8388608|LocationCount=2|X1=1290|Y1=598|X2=1350|Y2=598
|RECORD=27|IndexInSheet=430|OwnerPartId=-1|LineWidth=1|Color=8388608|LocationCount=2|X1=1350|Y1=628|X2=1290|Y2=628
|RECORD=27|IndexInSheet=431|OwnerPartId=-1|LineWidth=1|Color=8388608|LocationCount=2|X1=1350|Y1=638|X2=1290|Y2=638
|RECORD=27|IndexInSheet=432|OwnerPartId=-1|LineWidth=1|Color=8388608|LocationCount=2|X1=1350|Y1=858|X2=1290|Y2=858
|RECORD=27|IndexInSheet=433|OwnerPartId=-1|LineWidth=1|Color=8388608|LocationCount=2|X1=1350|Y1=868|X2=1290|Y2=868
|RECORD=27|IndexInSheet=434|OwnerPartId=-1|LineWidth=1|Color=8388608|LocationCount=9|X1=1290|Y1=948|X2=1320|Y2=948|X3=1320|Y3=898|X4=1320|Y4=848|X5=1320|Y5=798|X6=1320|Y6=748|X7=1320|Y7=698|X8=1320|Y8=648|X9=1320|Y9=568
|RECORD=27|IndexInSheet=435|OwnerPartId=-1|LineWidth=1|Color=8388608|LocationCount=9|X1=580|Y1=458|X2=620|Y2=458|X3=620|Y3=408|X4=620|Y4=358|X5=620|Y5=308|X6=620|Y6=258|X7=620|Y7=208|X8=620|Y8=158|X9=620|Y9=68
|RECORD=27|IndexInSheet=436|OwnerPartId=-1|LineWidth=1|Color=8388608|LocationCount=7|X1=1280|Y1=458|X2=1310|Y2=458|X3=1310|Y3=308|X4=1310|Y4=258|X5=1310|Y5=208|X6=1310|Y6=158|X7=1310|Y7=78
|RECORD=27|IndexInSheet=437|OwnerPartId=-1|LineWidth=1|Color=8388608|LocationCount=2|X1=640|Y1=778|X2=580|Y2=778
|RECORD=22|IndexInSheet=438|OwnerPartId=-1|Location.X=1170|Location.Y=788|Color=255|Orientation=1|Symbol=Thin Cross|IsActive=T|SuppressAll=T
|RECORD=22|IndexInSheet=439|OwnerPartId=-1|Location.X=1170|Location.Y=768|Color=255|Orientation=1|Symbol=Thin Cross|IsActive=T|SuppressAll=T
|RECORD=22|IndexInSheet=440|OwnerPartId=-1|Location.X=1170|Location.Y=738|Color=255|Orientation=1|Symbol=Thin Cross|IsActive=T|SuppressAll=T
|RECORD=27|IndexInSheet=441|OwnerPartId=-1|LineWidth=1|Color=8388608|LocationCount=2|X1=1170|Y1=728|X2=1060|Y2=728
|RECORD=22|IndexInSheet=442|OwnerPartId=-1|Location.X=460|Location.Y=498|Color=255|Orientation=1|Symbol=Thin Cross|IsActive=T|SuppressAll=T
|RECORD=22|IndexInSheet=443|OwnerPartId=-1|Location.X=580|Location.Y=498|Color=255|Orientation=1|Symbol=Thin Cross|IsActive=T|SuppressAll=T
|RECORD=29|IndexInSheet=-1|OwnerPartId=-1|Location.X=400|Location.Y=158|Color=128
|RECORD=29|IndexInSheet=-1|OwnerPartId=-1|Location.X=400|Location.Y=208|Color=128
|RECORD=29|IndexInSheet=-1|OwnerPartId=-1|Location.X=400|Location.Y=258|Color=128
|RECORD=29|IndexInSheet=-1|OwnerPartId=-1|Location.X=400|Location.Y=308|Color=128
|RECORD=29|IndexInSheet=-1|OwnerPartId=-1|Location.X=400|Location.Y=358|Color=128
|RECORD=29|IndexInSheet=-1|OwnerPartId=-1|Location.X=400|Location.Y=408|Color=128
|RECORD=29|IndexInSheet=-1|OwnerPartId=-1|Location.X=410|Location.Y=648|Color=128
|RECORD=29|IndexInSheet=-1|OwnerPartId=-1|Location.X=410|Location.Y=698|Color=128
|RECORD=29|IndexInSheet=-1|OwnerPartId=-1|Location.X=410|Location.Y=748|Color=128
|RECORD=29|IndexInSheet=-1|OwnerPartId=-1|Location.X=410|Location.Y=798|Color=128
|RECORD=29|IndexInSheet=-1|OwnerPartId=-1|Location.X=410|Location.Y=848|Color=128
|RECORD=29|IndexInSheet=-1|OwnerPartId=-1|Location.X=410|Location.Y=898|Color=128
|RECORD=29|IndexInSheet=-1|OwnerPartId=-1|Location.X=410|Location.Y=968|Color=128
|RECORD=29|IndexInSheet=-1|OwnerPartId=-1|Location.X=410|Location.Y=978|Color=128
|RECORD=29|IndexInSheet=-1|OwnerPartId=-1|Location.X=410|Location.Y=988|Color=128
|RECORD=29|IndexInSheet=-1|OwnerPartId=-1|Location.X=600|Location.Y=648|Color=128
|RECORD=29|IndexInSheet=-1|OwnerPartId=-1|Location.X=600|Location.Y=698|Color=128
|RECORD=29|IndexInSheet=-1|OwnerPartId=-1|Location.X=600|Location.Y=748|Color=128
|RECORD=29|IndexInSheet=-1|OwnerPartId=-1|Location.X=600|Location.Y=798|Color=128
|RECORD=29|IndexInSheet=-1|OwnerPartId=-1|Location.X=600|Location.Y=848|Color=128
|RECORD=29|IndexInSheet=-1|OwnerPartId=-1|Location.X=600|Location.Y=898|Color=128
|RECORD=29|IndexInSheet=-1|OwnerPartId=-1|Location.X=600|Location.Y=968|Color=128
|RECORD=29|IndexInSheet=-1|OwnerPartId=-1|Location.X=600|Location.Y=978|Color=128
|RECORD=29|IndexInSheet=-1|OwnerPartId=-1|Location.X=600|Location.Y=988|Color=128
|RECORD=29|IndexInSheet=-1|OwnerPartId=-1|Location.X=620|Location.Y=158|Color=128
|RECORD=29|IndexInSheet=-1|OwnerPartId=-1|Location.X=620|Location.Y=208|Color=128
|RECORD=29|IndexInSheet=-1|OwnerPartId=-1|Location.X=620|Location.Y=258|Color=128
|RECORD=29|IndexInSheet=-1|OwnerPartId=-1|Location.X=620|Location.Y=308|Color=128
|RECORD=29|IndexInSheet=-1|OwnerPartId=-1|Location.X=620|Location.Y=358|Color=128
|RECORD=29|IndexInSheet=-1|OwnerPartId=-1|Location.X=620|Location.Y=408|Color=128
|RECORD=29|IndexInSheet=-1|OwnerPartId=-1|Location.X=1110|Location.Y=158|Color=128
|RECORD=29|IndexInSheet=-1|OwnerPartId=-1|Location.X=1110|Location.Y=208|Color=128
|RECORD=29|IndexInSheet=-1|OwnerPartId=-1|Location.X=1110|Location.Y=258|Color=128
|RECORD=29|IndexInSheet=-1|OwnerPartId=-1|Location.X=1110|Location.Y=308|Color=128
|RECORD=29|IndexInSheet=-1|OwnerPartId=-1|Location.X=1110|Location.Y=338|Color=128
|RECORD=29|IndexInSheet=-1|OwnerPartId=-1|Location.X=1110|Location.Y=368|Color=128
|RECORD=29|IndexInSheet=-1|OwnerPartId=-1|Location.X=1110|Location.Y=398|Color=128
|RECORD=29|IndexInSheet=-1|OwnerPartId=-1|Location.X=1110|Location.Y=428|Color=128
|RECORD=29|IndexInSheet=-1|OwnerPartId=-1|Location.X=1130|Location.Y=648|Color=128
|RECORD=29|IndexInSheet=-1|OwnerPartId=-1|Location.X=1130|Location.Y=698|Color=128
|RECORD=29|IndexInSheet=-1|OwnerPartId=-1|Location.X=1130|Location.Y=748|Color=128
|RECORD=29|IndexInSheet=-1|OwnerPartId=-1|Location.X=1130|Location.Y=798|Color=128
|RECORD=29|IndexInSheet=-1|OwnerPartId=-1|Location.X=1130|Location.Y=848|Color=128
|RECORD=29|IndexInSheet=-1|OwnerPartId=-1|Location.X=1130|Location.Y=898|Color=128
|RECORD=29|IndexInSheet=-1|OwnerPartId=-1|Location.X=1160|Location.Y=938|Color=128
|RECORD=29|IndexInSheet=-1|OwnerPartId=-1|Location.X=1310|Location.Y=158|Color=128
|RECORD=29|IndexInSheet=-1|OwnerPartId=-1|Location.X=1310|Location.Y=208|Color=128
|RECORD=29|IndexInSheet=-1|OwnerPartId=-1|Location.X=1310|Location.Y=258|Color=128
|RECORD=29|IndexInSheet=-1|OwnerPartId=-1|Location.X=1310|Location.Y=308|Color=128
|RECORD=29|IndexInSheet=-1|OwnerPartId=-1|Location.X=1320|Location.Y=648|Color=128
|RECORD=29|IndexInSheet=-1|OwnerPartId=-1|Location.X=1320|Location.Y=698|Color=128
|RECORD=29|IndexInSheet=-1|OwnerPartId=-1|Location.X=1320|Location.Y=748|Color=128
|RECORD=29|IndexInSheet=-1|OwnerPartId=-1|Location.X=1320|Location.Y=798|Color=128
|RECORD=29|IndexInSheet=-1|OwnerPartId=-1|Location.X=1320|Location.Y=848|Color=128
|RECORD=29|IndexInSheet=-1|OwnerPartId=-1|Location.X=1320|Location.Y=898|Color=128